G04 ================== begin FILE IDENTIFICATION RECORD ==================*
G04 Layout Name:  12432-1.brd*
G04 Film Name:    L5VCC*
G04 File Format:  Gerber RS274X*
G04 File Origin:  Cadence Allegro 16.2-S037*
G04 Origin Date:  Wed Oct 17 11:00:08 2012*
G04 *
G04 Layer:  VIA CLASS/L5VCC*
G04 Layer:  PIN/L5VCC*
G04 Layer:  PACKAGE GEOMETRY/PWRVCC*
G04 Layer:  ETCH/L5VCC*
G04 Layer:  DRAWING FORMAT/LAYER_PCB_STORY*
G04 Layer:  DRAWING FORMAT/LAYER_L5VCC*
G04 *
G04 Offset:    (0.00 0.00)*
G04 Mirror:    No*
G04 Mode:      Negative*
G04 Rotation:  0*
G04 FullContactRelief:  No*
G04 UndefLineWidth:     6.00*
G04 ================== end FILE IDENTIFICATION RECORD ====================*
%FSLAX35Y35*MOIN*%
%IR0*IPPOS*OFA0.00000B0.00000*MIA0B0*SFA1.00000B1.00000*%
%ADD16O,.115X.072*%
%ADD14C,.032*%
%ADD11C,.036*%
%AMMACRO15*
4,1,15,.00398,.00044,
.003999,.000208,
.004004,-.000025,
.003996,-.000258,
.00398,-.00044,
.00483,-.00129,
.004897,-.001007,
.004947,-.000721,
.004981,-.000432,
.004997,-.000141,
.004997,.000149,
.00498,.00044,
.004946,.000729,
.004895,.001015,
.00483,.00129,
.00398,.00044,
0.0*
4,1,15,.00044,-.00398,
.000208,-.003999,
-.000025,-.004004,
-.000258,-.003996,
-.00044,-.00398,
-.00129,-.00483,
-.001007,-.004897,
-.000721,-.004947,
-.000432,-.004981,
-.000141,-.004997,
.000149,-.004997,
.00044,-.00498,
.000729,-.004946,
.001015,-.004895,
.00129,-.00483,
.00044,-.00398,
0.0*
4,1,15,-.00398,-.00044,
-.003999,-.000208,
-.004004,.000025,
-.003996,.000258,
-.00398,.00044,
-.00483,.00129,
-.004897,.001007,
-.004947,.000721,
-.004981,.000432,
-.004997,.000141,
-.004997,-.000149,
-.00498,-.00044,
-.004946,-.000729,
-.004895,-.001015,
-.00483,-.00129,
-.00398,-.00044,
0.0*
4,1,15,-.00044,.00398,
-.000208,.003999,
.000025,.004004,
.000258,.003996,
.00044,.00398,
.00129,.00483,
.001007,.004897,
.000721,.004947,
.000432,.004981,
.000141,.004997,
-.000149,.004997,
-.00044,.00498,
-.000729,.004946,
-.001015,.004895,
-.00129,.00483,
-.00044,.00398,
0.0*
%
%ADD15MACRO15*%
%ADD17C,.101*%
%ADD10C,.114*%
%ADD12C,.18*%
%ADD13C,.119*%
%ADD21C,.174*%
%ADD18C,.197*%
%AMMACRO20*
4,1,15,.00398,.00044,
.003999,.000208,
.004004,-.000025,
.003996,-.000258,
.00398,-.00044,
.00483,-.00129,
.004897,-.001007,
.004947,-.000721,
.004981,-.000432,
.004997,-.000141,
.004997,.000149,
.00498,.00044,
.004946,.000729,
.004895,.001015,
.00483,.00129,
.00398,.00044,
270.*
4,1,15,.00044,-.00398,
.000208,-.003999,
-.000025,-.004004,
-.000258,-.003996,
-.00044,-.00398,
-.00129,-.00483,
-.001007,-.004897,
-.000721,-.004947,
-.000432,-.004981,
-.000141,-.004997,
.000149,-.004997,
.00044,-.00498,
.000729,-.004946,
.001015,-.004895,
.00129,-.00483,
.00044,-.00398,
270.*
4,1,15,-.00398,-.00044,
-.003999,-.000208,
-.004004,.000025,
-.003996,.000258,
-.00398,.00044,
-.00483,.00129,
-.004897,.001007,
-.004947,.000721,
-.004981,.000432,
-.004997,.000141,
-.004997,-.000149,
-.00498,-.00044,
-.004946,-.000729,
-.004895,-.001015,
-.00483,-.00129,
-.00398,-.00044,
270.*
4,1,15,-.00044,.00398,
-.000208,.003999,
.000025,.004004,
.000258,.003996,
.00044,.00398,
.00129,.00483,
.001007,.004897,
.000721,.004947,
.000432,.004981,
.000141,.004997,
-.000149,.004997,
-.00044,.00498,
-.000729,.004946,
-.001015,.004895,
-.00129,.00483,
-.00044,.00398,
270.*
%
%ADD20MACRO20*%
%AMMACRO19*
4,1,15,.00398,.00044,
.003999,.000208,
.004004,-.000025,
.003996,-.000258,
.00398,-.00044,
.00483,-.00129,
.004897,-.001007,
.004947,-.000721,
.004981,-.000432,
.004997,-.000141,
.004997,.000149,
.00498,.00044,
.004946,.000729,
.004895,.001015,
.00483,.00129,
.00398,.00044,
180.*
4,1,15,.00044,-.00398,
.000208,-.003999,
-.000025,-.004004,
-.000258,-.003996,
-.00044,-.00398,
-.00129,-.00483,
-.001007,-.004897,
-.000721,-.004947,
-.000432,-.004981,
-.000141,-.004997,
.000149,-.004997,
.00044,-.00498,
.000729,-.004946,
.001015,-.004895,
.00129,-.00483,
.00044,-.00398,
180.*
4,1,15,-.00398,-.00044,
-.003999,-.000208,
-.004004,.000025,
-.003996,.000258,
-.00398,.00044,
-.00483,.00129,
-.004897,.001007,
-.004947,.000721,
-.004981,.000432,
-.004997,.000141,
-.004997,-.000149,
-.00498,-.00044,
-.004946,-.000729,
-.004895,-.001015,
-.00483,-.00129,
-.00398,-.00044,
180.*
4,1,15,-.00044,.00398,
-.000208,.003999,
.000025,.004004,
.000258,.003996,
.00044,.00398,
.00129,.00483,
.001007,.004897,
.000721,.004947,
.000432,.004981,
.000141,.004997,
-.000149,.004997,
-.00044,.00498,
-.000729,.004946,
-.001015,.004895,
-.00129,.00483,
-.00044,.00398,
180.*
%
%ADD19MACRO19*%
%ADD22C,.02*%
%ADD23C,.006*%
%ADD25C,.09706*%
%ADD24C,.11506*%
%ADD26C,.17006*%
G75*
%LPD*%
G75*
G36*
G01X-6000Y-6000D02*
X1039465D01*
Y1998126D01*
X-6000D01*
Y-6000D01*
G37*
%LPC*%
G75*
G36*
G01X1030461Y1686599D02*
X1028283Y1684421D01*
X1023228D01*
G03X1016287Y1677480I0J-6941D01*
G01Y1621265D01*
X1014109Y1619087D01*
X989744D01*
G03Y1608866I0J-5110D01*
G01X1014109D01*
X1016287Y1606688D01*
Y1432756D01*
G03X1023228Y1425815I6941J0D01*
G01X1028283D01*
X1030461Y1423637D01*
Y3937D01*
G02X1029528Y3004I-933J0D01*
G01X3937D01*
G02X3004Y3937I0J933D01*
G01Y408401D01*
X5182Y410579D01*
X19882D01*
G03Y424067I0J6744D01*
G01X5182D01*
X3004Y426245D01*
Y817849D01*
X5182Y820027D01*
X19882D01*
G03Y833516I0J6745D01*
G01X5182D01*
X3004Y835694D01*
Y1392653D01*
X5182Y1394831D01*
X19882D01*
G03Y1408319I0J6744D01*
G01X5182D01*
X3004Y1410497D01*
Y1802101D01*
X5182Y1804279D01*
X19882D01*
G03Y1817768I0J6744D01*
G01X5182D01*
X3004Y1819946D01*
Y1988189D01*
G02X3937Y1989122I933J0D01*
G01X1029528D01*
G02X1030461Y1988189I0J-933D01*
G01Y1686599D01*
G37*
%LPD*%
G75*
G54D25*
X78150Y28858D03*
Y178464D03*
Y434370D03*
Y583976D03*
Y839882D03*
Y989488D03*
Y1245394D03*
Y1395000D03*
Y1650906D03*
Y1800512D03*
X158071Y191614D03*
Y341220D03*
Y597126D03*
Y746732D03*
Y1002638D03*
Y1152244D03*
Y1408150D03*
Y1557756D03*
Y1813662D03*
Y1963268D03*
X886417Y191614D03*
Y341220D03*
Y597126D03*
Y746732D03*
Y1002638D03*
Y1152244D03*
Y1408150D03*
Y1557756D03*
Y1813662D03*
Y1963268D03*
G54D24*
X9843Y353144D03*
Y717711D03*
Y762617D03*
Y875216D03*
Y1337396D03*
Y1701963D03*
Y1746869D03*
Y1859468D03*
G54D26*
X1019291Y1416024D03*
Y1694212D03*
G54D16*
X68898Y17047D03*
Y190275D03*
Y422559D03*
Y595787D03*
Y828071D03*
Y1001299D03*
Y1233583D03*
Y1406811D03*
Y1639095D03*
Y1812323D03*
X167323Y179803D03*
Y353031D03*
Y585315D03*
Y758543D03*
Y990827D03*
Y1164055D03*
Y1396339D03*
Y1569567D03*
Y1801851D03*
Y1975079D03*
X895669Y179803D03*
Y353031D03*
Y585315D03*
Y758543D03*
Y990827D03*
Y1164055D03*
Y1396339D03*
Y1569567D03*
Y1801851D03*
Y1975079D03*
G54D14*
X14999Y1936050D03*
Y1940050D03*
X8499Y1937550D03*
X15099Y1944050D03*
X5303Y1947050D03*
X11703Y1951946D03*
X17499Y1961050D03*
X29699Y388484D03*
X29599Y382884D03*
X23399Y373931D03*
Y389679D03*
X23499Y381831D03*
X26299Y383854D03*
Y387629D03*
X28100Y374000D03*
X26299Y399601D03*
Y403376D03*
X29999Y398684D03*
X29899Y404384D03*
X23799Y405684D03*
X23499Y397579D03*
X35900Y412600D03*
X26524Y426720D03*
X26399Y423322D03*
X28672Y429356D03*
X29365Y421169D03*
X23399Y429051D03*
X28900Y417800D03*
X26492Y439350D03*
X26599Y442749D03*
X26899Y454850D03*
X28700Y451900D03*
X28800Y436700D03*
X28700Y445700D03*
X23399Y444799D03*
X23499Y452699D03*
Y436951D03*
X26799Y458497D03*
X26486Y462648D03*
X26499Y466250D03*
X29500Y460800D03*
X23499Y468447D03*
X23399Y476295D03*
Y460547D03*
X26299Y478404D03*
X26515Y481798D03*
X23399Y492043D03*
X23499Y484195D03*
X36499Y517775D03*
X26399Y501966D03*
Y505741D03*
X28600Y508500D03*
X38400Y514955D03*
X28664Y499429D03*
X23499Y515691D03*
Y499943D03*
X23399Y507791D03*
X36499Y521550D03*
X35338Y524746D03*
X26691Y532701D03*
X22800Y539600D03*
X23399Y523539D03*
X23499Y531439D03*
X26599Y525648D03*
Y529302D03*
X27199Y539600D03*
X39217Y554750D03*
X33307Y557938D03*
X26199Y547176D03*
X29999Y557150D03*
X33699Y561850D03*
X36499Y566350D03*
X22699Y577950D03*
X22999Y565550D03*
X28000Y578500D03*
X25581Y567763D03*
X27699Y573750D03*
X22978Y588571D03*
X28808Y593150D03*
X28700Y596549D03*
X27499Y620203D03*
Y623857D03*
X37999Y611550D03*
X26869Y616861D03*
X23499Y618053D03*
X23999Y609250D03*
X34976Y619250D03*
X26800Y611500D03*
X32200Y603710D03*
X31598Y607102D03*
X39600Y626984D03*
X38300Y633800D03*
X30712Y624971D03*
X29999Y640550D03*
X29819Y634951D03*
X23399Y641649D03*
X23799Y625950D03*
X23499Y633801D03*
X26568Y635950D03*
Y639604D03*
X30999Y656250D03*
Y650550D03*
X23499Y665297D03*
Y649549D03*
X23725Y657471D03*
X26737Y651957D03*
X26999Y656550D03*
X23699Y673150D03*
X23499Y681045D03*
X27687Y667447D03*
Y671101D03*
X27700Y682700D03*
X29999Y694550D03*
X25999Y694870D03*
X23999Y689050D03*
X27299Y783550D03*
X35300Y789375D03*
X32800Y803050D03*
X37416Y799033D03*
X37099Y811350D03*
X26299Y815050D03*
X35559Y795112D03*
X31699Y814350D03*
X37216Y807951D03*
X39649Y822000D03*
X29299Y836901D03*
X40400Y840792D03*
X22500Y853700D03*
X29600Y854000D03*
X23299Y863050D03*
X26662Y861550D03*
X25000Y858100D03*
X20400Y1048300D03*
X20999Y1320550D03*
X23700Y1354600D03*
X20999Y1352050D03*
X25000Y1357742D03*
X22851Y1374169D03*
X22999Y1366050D03*
X23499Y1381550D03*
X25507Y1372045D03*
X25558Y1368447D03*
X32550Y1392777D03*
X27499Y1387550D03*
X24499Y1389663D03*
X28499Y1391050D03*
X32333Y1389383D03*
X30500Y1395500D03*
X33321Y1414755D03*
X29786Y1414858D03*
X23499Y1421550D03*
X23999Y1413550D03*
X32451Y1411468D03*
X28999Y1411550D03*
X32094Y1448448D03*
X28697Y1448296D03*
X36198Y1446749D03*
X27099Y1444350D03*
X30999Y1438050D03*
X27999Y1430050D03*
X23499Y1445050D03*
X22999Y1437050D03*
X23999Y1429050D03*
X33206Y1432352D03*
X30499Y1434550D03*
X30378Y1462518D03*
X33915Y1462681D03*
X29069Y1459379D03*
X36791Y1460866D03*
X23028Y1468579D03*
X23499Y1460550D03*
X22999Y1453050D03*
X34465Y1481683D03*
X30999Y1482050D03*
X32520Y1485092D03*
X28999Y1478050D03*
X23599Y1476350D03*
X23277Y1484050D03*
X34099Y1497550D03*
X30499D03*
X27499Y1495050D03*
X36999Y1494550D03*
X22999Y1500050D03*
X23799Y1508050D03*
X24499Y1492050D03*
X30115Y1511900D03*
X33512Y1512051D03*
X29631Y1533063D03*
X31999Y1517846D03*
Y1521500D03*
X35245Y1522512D03*
X35999Y1514550D03*
X29765Y1515282D03*
X24423Y1527123D03*
X22999Y1515550D03*
X37999Y1530900D03*
X24199Y1523700D03*
X25247Y1546912D03*
X38500Y1534600D03*
X32099Y1535550D03*
X26705Y1534795D03*
X30199Y1545450D03*
X36340Y1558809D03*
X34896Y1555730D03*
X38208Y1569841D03*
X25521Y1563350D03*
X30520Y1572049D03*
X24999Y1569550D03*
X31149Y1568300D03*
X23608Y1572653D03*
X24323Y1559950D03*
X27123Y1572205D03*
X39000Y1573500D03*
X34999Y1595350D03*
X22699Y1594224D03*
X31099Y1595350D03*
X28899Y1613524D03*
X32299D03*
X26999Y1610550D03*
X34884Y1615734D03*
X23499Y1618050D03*
Y1610050D03*
Y1602050D03*
X33599Y1600200D03*
X29499Y1630050D03*
X32199Y1633124D03*
X34816Y1630953D03*
X22999Y1626050D03*
X23499Y1634050D03*
X32663Y1628181D03*
X31999Y1661127D03*
X28600Y1661039D03*
X29626Y1645002D03*
X33026Y1645051D03*
X27499Y1657050D03*
X32989Y1648451D03*
X26785Y1642089D03*
X23499Y1657050D03*
X23999Y1649550D03*
X23415Y1641634D03*
X34699Y1663300D03*
X22999Y1665550D03*
X24244Y1681868D03*
X22864Y1673550D03*
X32700Y1673300D03*
X32494Y1669706D03*
X29100Y1669500D03*
X30500Y1697500D03*
X39900Y1751200D03*
X41200Y1747050D03*
X30274Y1787238D03*
X35675Y1783450D03*
X39324Y1780623D03*
X38094Y1785840D03*
X38878Y1799571D03*
X34599Y1805123D03*
X37699Y1789850D03*
X37574Y1794050D03*
X31811Y1790271D03*
X40478Y1795820D03*
X32099Y1797150D03*
X28550Y1828153D03*
X29899Y1821050D03*
X34099Y1822850D03*
X35876Y1812350D03*
X34129Y1815267D03*
X36532Y1825352D03*
X36399Y1828750D03*
X26099Y1824950D03*
X29599Y1844350D03*
X22099Y1836609D03*
X28123Y1831527D03*
X25999Y1842550D03*
X39699Y1833850D03*
X28799Y1919060D03*
X23030Y1922038D03*
X26765Y1921945D03*
X34799Y1946750D03*
X38703Y1946754D03*
X25499Y1956050D03*
X32999Y1960555D03*
X31799Y1979050D03*
X41999Y200050D03*
X45800Y405200D03*
X61400Y452600D03*
X62497Y474346D03*
X60003Y534150D03*
X59999Y537550D03*
X42867Y548450D03*
X43099Y555850D03*
X46299Y552950D03*
X49799Y559150D03*
X42599Y567850D03*
X47543Y578340D03*
X44959Y575756D03*
X60076Y595777D03*
X55499Y595650D03*
X42202Y608195D03*
X41400Y611500D03*
X47626Y611300D03*
X45701Y607700D03*
X42709Y625607D03*
X41500Y642800D03*
X57800Y634300D03*
X44900Y642800D03*
X47101Y632355D03*
X41500Y635000D03*
X52500D03*
X48999Y642900D03*
X50410Y695801D03*
X50300Y699200D03*
X45100Y793100D03*
X44046Y799554D03*
X46887Y803413D03*
X51100Y806300D03*
X49900Y813200D03*
X56281Y801350D03*
X50399Y836250D03*
X46700Y820100D03*
X54074Y815750D03*
X62405Y820300D03*
X46576Y832951D03*
X48346Y844529D03*
X58699Y837250D03*
X44697Y1546793D03*
X44299Y1550950D03*
X42199Y1601050D03*
X47400Y1721700D03*
X42000Y1740100D03*
X47717Y1731337D03*
X47800Y1740500D03*
X45877Y1728477D03*
Y1724823D03*
X47000Y1737100D03*
X43600D03*
X42275Y1754000D03*
X45799Y1757650D03*
X47440Y1761391D03*
X47400Y1765250D03*
X43751Y1780559D03*
X46999Y1779550D03*
X46199Y1783050D03*
X43925Y1767890D03*
X47604Y1769005D03*
X45782Y1771877D03*
X47499Y1775350D03*
X47899Y1798650D03*
X48049Y1791450D03*
X42199Y1792250D03*
X46799Y1794900D03*
X61009Y1822340D03*
X60449Y1842550D03*
X46499Y1836550D03*
X47166Y1839884D03*
X43099Y1833850D03*
X57999Y1891050D03*
X42499Y1902550D03*
X48499Y1897050D03*
X44368Y1951450D03*
X44399Y1942250D03*
X42532Y1946783D03*
X53999Y1946650D03*
X50299D03*
X46565Y1946703D03*
X45999Y1971450D03*
X50499Y1961550D03*
X43462Y1961160D03*
X78700Y74200D03*
Y70700D03*
X74999Y70550D03*
Y74050D03*
X74499Y80650D03*
Y84050D03*
X65999Y216050D03*
X65000Y455500D03*
X62503Y470946D03*
X66199Y475184D03*
Y469884D03*
X77499Y469550D03*
X62978Y486217D03*
X63067Y489616D03*
X66299Y490784D03*
Y485484D03*
X77999Y493050D03*
X77499Y502550D03*
X65599Y514250D03*
X63499Y538550D03*
Y533050D03*
X68000Y546500D03*
X72500Y545000D03*
X81251Y607249D03*
Y619251D03*
X82499Y627050D03*
X80499Y664550D03*
X74499Y662050D03*
X78499Y654050D03*
X76999Y664550D03*
X81999Y668050D03*
X65500Y817700D03*
X80500Y817000D03*
X76540Y850938D03*
X75500Y847700D03*
X68860Y838706D03*
X69499Y842950D03*
X63499Y843050D03*
X74220Y854150D03*
X72362Y849550D03*
X80699Y1004450D03*
Y1000450D03*
X72000Y1013400D03*
X63273Y1023974D03*
X66499Y1025050D03*
X75500Y1012261D03*
X65486Y1031515D03*
X80000Y1090500D03*
X74500Y1097550D03*
X79899Y1104550D03*
X74399Y1111550D03*
X76999Y1196550D03*
X78499Y1273550D03*
X78613Y1282664D03*
X78779Y1302664D03*
Y1312664D03*
X77758Y1357742D03*
X76000Y1431100D03*
X80043Y1544691D03*
X78600Y1561900D03*
X75000Y1561800D03*
X74400Y1574800D03*
X80400Y1571766D03*
X82329Y1568117D03*
X79000Y1555500D03*
X82429D03*
X74800Y1584700D03*
X78100Y1688189D03*
X74500Y1692000D03*
X74400Y1778100D03*
X80099Y1817250D03*
X80999Y1836550D03*
X93999Y58550D03*
X92900Y66128D03*
X92999Y86128D03*
X97499Y90050D03*
X92999Y96128D03*
X89603Y132629D03*
X86899Y130567D03*
X86599Y126750D03*
X95350Y204550D03*
X89800Y208550D03*
X96900Y510000D03*
X93200Y510500D03*
X95500Y513400D03*
X98900D03*
X83700Y529500D03*
X88999Y538050D03*
X104502Y530552D03*
X86199Y536025D03*
Y532250D03*
X89000Y816500D03*
X90000Y826000D03*
X90500Y831500D03*
X98700Y822550D03*
X98000Y833500D03*
X98700Y842600D03*
X92999Y868550D03*
X92499Y876550D03*
X94999Y901550D03*
X89469Y935588D03*
X85999Y940429D03*
X86399Y937050D03*
X89499Y942850D03*
X102100Y968500D03*
X99000Y965000D03*
X104600Y980500D03*
X90000Y993100D03*
X92600Y996100D03*
X88000Y1008500D03*
X101499Y1072550D03*
X103999Y1216863D03*
X102900Y1196050D03*
X103686Y1223863D03*
X101541Y1262607D03*
X101399Y1292550D03*
X102700Y1321363D03*
X102000Y1341000D03*
X91279Y1340642D03*
X86165Y1339050D03*
X86890Y1342860D03*
X101500Y1352000D03*
X89999Y1348050D03*
X86890Y1346635D03*
X102350Y1344500D03*
Y1348154D03*
X97229Y1373337D03*
X97000Y1377600D03*
X98599Y1491350D03*
X100699Y1471050D03*
X100499Y1479650D03*
X83932Y1544705D03*
X100800Y1536450D03*
X96200Y1550100D03*
X99899Y1539850D03*
X100000Y1546650D03*
X90324Y1538800D03*
X97499Y1554550D03*
X98144Y1534309D03*
X96999Y1558050D03*
X89373Y1561073D03*
X85600Y1561500D03*
X95499Y1665418D03*
X92900Y1678176D03*
X93999Y1703050D03*
X92873Y1708176D03*
X92479Y1718176D03*
X89306Y1746856D03*
X89499Y1753575D03*
X85341Y1752245D03*
X85194Y1748848D03*
X99199Y1761899D03*
X99999Y1753575D03*
X101399Y1784700D03*
X85599Y1797350D03*
X96600Y1826000D03*
X86649Y1817100D03*
X90000Y1827900D03*
X93500D03*
X97999Y1843050D03*
X112999Y124050D03*
X111790Y132259D03*
X115876Y125973D03*
Y130050D03*
X114900Y177900D03*
X122397Y252688D03*
X122799Y249150D03*
X124999Y246050D03*
X123378Y255944D03*
X107499Y497050D03*
X107526Y528996D03*
X109400Y543200D03*
X106000D03*
X105100Y600000D03*
X107000Y604800D03*
X125499Y635550D03*
Y638950D03*
X124999Y643050D03*
X110500Y790200D03*
X111100Y813400D03*
X111200Y799450D03*
X111207Y810001D03*
X110700Y795700D03*
X111089Y806603D03*
X110800Y803100D03*
X110499Y834550D03*
X106749Y934367D03*
X108441Y924705D03*
X108845Y931657D03*
X109099Y928250D03*
X108200Y963600D03*
X107300Y986000D03*
X107400Y992900D03*
X124100Y1047100D03*
X123999Y1054050D03*
Y1050650D03*
X120100Y1053200D03*
X116700Y1063500D03*
X112699Y1058974D03*
X105499Y1080550D03*
X106718Y1076050D03*
X105999Y1085800D03*
X121500Y1083600D03*
X121100Y1075300D03*
X117499Y1079300D03*
X105600Y1069500D03*
X124423Y1077523D03*
Y1081177D03*
X120749Y1093990D03*
X125900Y1091282D03*
X116249Y1102550D03*
X112999Y1103740D03*
X123999Y1102550D03*
X108999Y1102050D03*
X106999Y1194550D03*
X106162Y1205702D03*
X114999Y1210363D03*
X118999Y1219050D03*
X123970Y1221573D03*
X119399Y1298113D03*
X116999Y1288050D03*
X120507Y1317050D03*
X111499Y1311800D03*
X107999Y1307713D03*
X116499Y1328013D03*
X120507Y1328096D03*
X113000Y1341000D03*
X107228Y1330552D03*
X107500Y1340500D03*
X109228Y1337090D03*
Y1333315D03*
X119499Y1339050D03*
X113500Y1352000D03*
X110499Y1365050D03*
X109999Y1355050D03*
X112440Y1358196D03*
X112999Y1361550D03*
X121000Y1364000D03*
X113500Y1344500D03*
Y1348154D03*
X125100Y1366000D03*
X117390Y1426201D03*
X119507Y1423540D03*
X117390Y1429976D03*
X104935Y1440634D03*
X104999Y1444941D03*
X107328Y1438218D03*
X114499Y1432050D03*
X107999Y1448050D03*
X124290Y1469241D03*
X123808Y1465050D03*
X106999Y1454450D03*
X105099Y1459150D03*
X123999Y1473050D03*
X122199Y1476050D03*
X118499Y1694050D03*
X117499Y1706050D03*
X109499Y1712213D03*
X104999Y1708963D03*
X117249Y1712090D03*
X112753Y1716613D03*
X122642Y1704243D03*
X112562Y1720613D03*
X123749Y1711550D03*
X109499Y1743550D03*
X107499Y1736550D03*
X109399Y1739550D03*
X106999Y1746290D03*
X110099Y1759875D03*
X123393Y1870859D03*
X123592Y1874254D03*
X127999Y157050D03*
X147099Y245350D03*
X141499Y427550D03*
Y423050D03*
X135499Y517550D03*
X138999Y524213D03*
X137899Y545451D03*
X138416Y553500D03*
X140940Y561800D03*
X141300Y565900D03*
X127999Y645550D03*
X131400Y644600D03*
X144238Y645356D03*
X128725Y636626D03*
X128479Y640589D03*
X141773Y643013D03*
X144238Y649131D03*
X140499Y649350D03*
X134300Y646400D03*
X141500Y711000D03*
X137100Y1084800D03*
X140800Y1076300D03*
X137481Y1077557D03*
X137477Y1081177D03*
X132499Y1094550D03*
X138600Y1124600D03*
X130699Y1210653D03*
X135850Y1322250D03*
X125999Y1315550D03*
X132999Y1319550D03*
X142667Y1319218D03*
X133475Y1331200D03*
X140000Y1332600D03*
X138000Y1359025D03*
X129000Y1356500D03*
X142999Y1456373D03*
X139815Y1454438D03*
X139235Y1460973D03*
X127898Y1462441D03*
X142900Y1460000D03*
X133090Y1699959D03*
X128749Y1703300D03*
X131999Y1710050D03*
X141500Y1715500D03*
X135499Y1710150D03*
X141999Y1764550D03*
X137999Y1861497D03*
Y1865151D03*
X141101Y1866545D03*
X140999Y1859550D03*
X135999Y1881550D03*
X152499Y149550D03*
X154200Y168500D03*
X149400Y166400D03*
X149999Y243504D03*
Y239729D03*
X157440Y283924D03*
Y303924D03*
Y313924D03*
X165699Y428050D03*
X153459Y427494D03*
X154101Y445550D03*
X159600Y446399D03*
X163549Y517100D03*
X152000Y520813D03*
X163449Y521650D03*
X149000Y537500D03*
X160932Y549468D03*
X150750Y540416D03*
X156500Y554000D03*
X157000Y573851D03*
X160824Y577000D03*
X161000Y639100D03*
X158885Y679436D03*
Y689436D03*
X158385Y719436D03*
X159500Y814700D03*
X165499Y815550D03*
X153500Y834600D03*
X154799Y838050D03*
X153499Y918550D03*
X163500Y937100D03*
X160399Y922850D03*
X152500Y960000D03*
X154749Y979149D03*
Y968249D03*
X164700Y1085400D03*
X159000Y1083000D03*
X157700Y1114948D03*
X157600Y1124948D03*
X149562Y1315987D03*
X147400Y1321600D03*
X148024Y1333525D03*
X150338Y1453958D03*
X152499Y1462940D03*
X157440Y1490460D03*
Y1500460D03*
Y1520460D03*
Y1530460D03*
X157400Y1596550D03*
X160200Y1598500D03*
X165575Y1676975D03*
X152633Y1677967D03*
X150999Y1713550D03*
X165900Y1790500D03*
X161900Y1793400D03*
X159421Y1925972D03*
X175999Y82428D03*
X174999Y79050D03*
X175499Y86572D03*
X176399Y94872D03*
X178999Y79050D03*
X186999Y99050D03*
X169999Y129050D03*
X188999Y120800D03*
X173499Y149050D03*
X173500Y166315D03*
X187699Y492850D03*
X173100Y483100D03*
X172499Y491053D03*
X176799Y493850D03*
X188000Y484500D03*
X171722Y513827D03*
X182499Y532550D03*
X168453Y527949D03*
X183499Y556100D03*
X172660Y815731D03*
X169106Y815865D03*
X174199Y841050D03*
X172500Y919294D03*
X171100Y935000D03*
X171000Y939500D03*
X172000Y961000D03*
X170250Y948500D03*
X179499Y1275550D03*
X181000Y1365500D03*
X180500Y1369900D03*
X179999Y1655887D03*
X171999Y1662250D03*
X169600Y1682300D03*
X169100Y1685800D03*
X181100Y1682700D03*
X177900Y1690400D03*
X205938Y72528D03*
X201499Y104550D03*
X205499Y105550D03*
X207999Y109550D03*
X197899Y165075D03*
X199900Y554050D03*
X193549Y575875D03*
X200000Y818000D03*
X200539Y890300D03*
X200799Y896600D03*
X198924Y975975D03*
X199149Y1362900D03*
X194700Y1385700D03*
X193500Y1647000D03*
X201499Y1781050D03*
X194049Y1792600D03*
X210605Y70692D03*
X210685Y74725D03*
X215138Y72559D03*
X210634Y66863D03*
X210638Y62959D03*
X225499Y68550D03*
X210738Y82159D03*
Y78459D03*
X230749Y76300D03*
X213499Y104650D03*
X223499Y108150D03*
X218499Y190550D03*
X225298Y281114D03*
X213499Y283864D03*
X214063Y318114D03*
X213400Y355300D03*
X224998Y357049D03*
X220000Y516400D03*
X216999Y686550D03*
X213999Y725050D03*
X230849Y726050D03*
X228999Y765550D03*
X218224Y765325D03*
X211750Y894600D03*
X229562Y904113D03*
X215499Y905550D03*
X221800Y1069300D03*
X221300Y1083238D03*
X229800Y1073600D03*
X226800Y1093400D03*
X229025Y1471576D03*
X227814Y1887513D03*
X223436Y1890465D03*
X229800Y1875700D03*
X218100Y1886400D03*
X214999Y1909550D03*
X213562Y1926113D03*
X220062Y1931113D03*
X213138Y1952703D03*
X210999Y1942050D03*
X246999Y51550D03*
X246499Y42550D03*
X246999Y69550D03*
Y60550D03*
X246499Y86050D03*
Y80550D03*
X245499Y100550D03*
X233749Y110800D03*
X237899Y107050D03*
X250300Y275100D03*
X250400Y283100D03*
X239600Y278600D03*
X231800Y318414D03*
X233998Y357549D03*
X239400Y357400D03*
X249700Y682500D03*
X238500Y680800D03*
X249800Y689900D03*
X252499Y726050D03*
X241600Y765700D03*
X236800Y765800D03*
X233500Y1066100D03*
X242000Y1066000D03*
X251500Y1136700D03*
X241000Y1469600D03*
X233700Y1481600D03*
X232650Y1493450D03*
X232314Y1890513D03*
X236225Y1883125D03*
X231999Y1914050D03*
X249600Y1896800D03*
X249499Y1928050D03*
X240964Y1934113D03*
X253999Y44050D03*
X253871Y291410D03*
X252935Y319114D03*
X254499Y697700D03*
X255000Y1125700D03*
X256000Y1133000D03*
X269500Y1135500D03*
X261999Y1516050D03*
X257499Y1911050D03*
X264499Y1964050D03*
X291999Y94050D03*
X282800Y87500D03*
X293999Y293550D03*
X284999Y338650D03*
X281499Y338550D03*
X294500Y339000D03*
X279939Y728610D03*
X285499Y745050D03*
X282099D03*
X292999Y743650D03*
X277039Y740300D03*
X282500Y1135000D03*
X295000Y1513000D03*
X289999Y1554650D03*
X293700Y1553351D03*
X276039Y1551300D03*
X283499Y1556050D03*
X279999D03*
X291400Y1561500D03*
X285499Y1930050D03*
X288709Y1948042D03*
X284999Y1947691D03*
X280689Y1942710D03*
X296099Y17100D03*
X305099Y17000D03*
X311400Y17100D03*
X308999Y87050D03*
X297499Y97550D03*
X315800Y100500D03*
X298800Y333000D03*
X301249Y346050D03*
X313039Y352350D03*
X308999Y716450D03*
X315999Y718950D03*
X298000Y743500D03*
X310999Y757050D03*
X314999Y1527550D03*
X297800Y1561600D03*
X312999Y1566050D03*
X310249Y1569800D03*
X313499Y1919050D03*
X310499Y1957050D03*
X315999Y1958550D03*
X317000Y17300D03*
X324800Y89400D03*
X326499Y334054D03*
Y337454D03*
X321900Y364600D03*
X327999Y740550D03*
X323249Y749010D03*
X327749Y744050D03*
X324959Y766750D03*
X329499Y801550D03*
X330540Y795509D03*
X320499Y798050D03*
X326500Y1550200D03*
X324000Y1562500D03*
X330300Y1561200D03*
X323999Y1577250D03*
X325221Y1927272D03*
X331622Y1944767D03*
X329999Y1952273D03*
X332103Y1948133D03*
X327100Y1966472D03*
X343499Y31650D03*
X354999Y72050D03*
X343499Y60150D03*
X341499Y63050D03*
Y67110D03*
X357503Y77043D03*
X344520Y406329D03*
X350499Y597300D03*
Y715050D03*
X340699Y1046086D03*
X345499Y1096550D03*
X345424Y1310050D03*
X347324Y1524000D03*
X354500Y1559500D03*
X349774Y1582900D03*
X354000Y1584900D03*
X353499Y1710450D03*
X348499Y1762050D03*
X342999Y1947409D03*
X342621Y1943409D03*
X358999Y61550D03*
X374499Y77550D03*
X365499Y86550D03*
X371999Y549300D03*
X375999Y698550D03*
X371500Y880600D03*
X364499Y1099050D03*
X372999Y1123550D03*
X370149Y1320050D03*
X366149Y1554050D03*
X377900Y1703800D03*
X398799Y36152D03*
X381999Y50150D03*
X382339Y41610D03*
X381999Y53550D03*
X394199Y45050D03*
X381999Y57050D03*
X385999Y78050D03*
X400499Y406329D03*
X394649Y630600D03*
X390999Y1514398D03*
Y1517798D03*
X385499Y1735050D03*
X401499Y80550D03*
X402499Y1476850D03*
X400999Y1575550D03*
X645549Y1815134D03*
X644360Y1819137D03*
X659549Y1810634D03*
X690249Y1805634D03*
X707600Y1815600D03*
X711652Y1822109D03*
X711848Y1825504D03*
X732549Y1806634D03*
X733149Y1798634D03*
X733049Y1814134D03*
X752999Y746842D03*
X757499Y745342D03*
Y1079550D03*
X755600Y1149800D03*
X758499Y1371050D03*
X757999Y1484050D03*
X758199Y1553650D03*
X755000Y1825000D03*
X758499Y1893550D03*
X759114Y1957673D03*
X770999Y302050D03*
Y290050D03*
Y295550D03*
X763571Y295622D03*
X777999Y296050D03*
X772499Y323050D03*
X772873Y326924D03*
X760778Y345050D03*
X768178Y333964D03*
X780499Y330050D03*
X771105Y722789D03*
X766499Y732842D03*
X762999Y734550D03*
X769999Y733050D03*
X771999Y1124550D03*
X772499Y1130050D03*
X779499Y1131050D03*
X767083Y1134550D03*
X768199Y1138590D03*
X774542Y1530050D03*
X774577Y1533796D03*
X771225Y1539474D03*
X767936Y1540336D03*
X774500Y1788000D03*
X770999Y1820550D03*
X771499Y1936550D03*
X767999Y1945173D03*
X764908Y1946592D03*
X771499Y1940050D03*
X785499Y291050D03*
X786978Y298529D03*
X791499Y333050D03*
X789999Y336550D03*
X784499Y334050D03*
X781999Y725550D03*
X788999Y736050D03*
X791999Y733050D03*
X784939Y733550D03*
X792154Y1135926D03*
X784439Y1136550D03*
X789499Y1138050D03*
X784499Y1529050D03*
X784577Y1535628D03*
X791499Y1543550D03*
X793999Y1541050D03*
X788000Y1788000D03*
X793000Y1803500D03*
X795849Y1805500D03*
X791999Y1819050D03*
X783499Y1827050D03*
X802499Y1951550D03*
X800431Y1941193D03*
X785939Y1946800D03*
X792499Y1949050D03*
X794499Y1941050D03*
X782999Y1937050D03*
X802099Y1961950D03*
X820749Y163850D03*
X813249Y163800D03*
X821999Y193116D03*
X809940Y264940D03*
X822100Y261700D03*
Y279500D03*
X816700Y274300D03*
X820600Y664300D03*
X808660Y667540D03*
X813200Y675900D03*
X807000Y1072900D03*
X815400Y1078800D03*
X803199Y1151850D03*
X822100Y1466800D03*
X809960Y1478040D03*
X814700Y1486300D03*
X804899Y1556950D03*
X812000Y1799500D03*
X821249Y1791250D03*
X811000Y1793000D03*
X822499Y1815164D03*
X807000Y1822300D03*
X803500Y1822708D03*
X822700Y1871100D03*
X810900Y1882440D03*
X805900Y1887560D03*
X841499Y135550D03*
X827499Y163550D03*
X839249Y164050D03*
X829917Y216200D03*
X833576Y215432D03*
X837999Y219550D03*
X842499Y280924D03*
X836500Y274950D03*
X827499Y313424D03*
X835150Y677650D03*
X825800Y1072300D03*
X836625Y1487400D03*
X834799Y1946950D03*
X861999Y146550D03*
X854400Y264600D03*
X847878Y250040D03*
X851278Y249974D03*
X847450Y246666D03*
X850999Y246550D03*
X858478Y274050D03*
X865499Y288050D03*
X851172Y655432D03*
X847772Y655370D03*
X851197Y652032D03*
X847493Y651981D03*
X852696Y671197D03*
X850833Y1061441D03*
X847233Y1061492D03*
X847355Y1058094D03*
X851042Y1058047D03*
X852333Y1077716D03*
X860133Y1084142D03*
X864499Y1128750D03*
X860799Y1358925D03*
X861849Y1376050D03*
X848888Y1466402D03*
X852288Y1466346D03*
X848861Y1462463D03*
X852429Y1462948D03*
X854327Y1477550D03*
X858827Y1485696D03*
X863699Y1501250D03*
X862800Y1712700D03*
X851500Y1821400D03*
X849375Y1824982D03*
X854905Y1825583D03*
X853499Y1871036D03*
X850099Y1871056D03*
X854480Y1867578D03*
X849999Y1867550D03*
X863788Y1866953D03*
X865501Y1858747D03*
X859314Y1891365D03*
X854814Y1883550D03*
X863699Y1906450D03*
X857099Y1917650D03*
X882499Y147050D03*
X867500Y163924D03*
X867576Y159924D03*
X878078Y240103D03*
Y243878D03*
X874928Y238822D03*
X874790Y244748D03*
X871999Y283924D03*
X872136Y273924D03*
X886600Y303924D03*
X868799Y294750D03*
X867899Y321550D03*
X886200Y313924D03*
X868299Y336150D03*
X879750Y570550D03*
X879950Y565050D03*
X878596Y645573D03*
X874999Y644550D03*
X878596Y649348D03*
X875270Y650059D03*
X883083Y979183D03*
X879708Y971892D03*
X878233Y1051095D03*
X877964Y1054485D03*
X874733Y1055792D03*
X874999Y1049550D03*
X872086Y1084948D03*
X871999Y1094948D03*
X871499Y1124948D03*
X872086Y1114948D03*
X866700Y1379796D03*
X866596Y1375796D03*
X878054Y1456450D03*
X877853Y1459991D03*
X874499Y1460550D03*
X874986Y1454983D03*
X872086Y1490460D03*
X871999Y1500460D03*
Y1520460D03*
X872086Y1530460D03*
X867523Y1542821D03*
X867199Y1535150D03*
X886439Y1717600D03*
X873800Y1733600D03*
X879700Y1786300D03*
X879664Y1782213D03*
X866914Y1861840D03*
Y1865615D03*
X871921Y1905972D03*
X871421Y1895972D03*
X872086Y1925972D03*
Y1935972D03*
X901499Y92050D03*
X897555Y90494D03*
X898999Y99050D03*
X902499Y110550D03*
X898999D03*
X907499Y131800D03*
X896999Y141550D03*
X902999Y556050D03*
X900499Y962100D03*
X900999Y979050D03*
X889800Y1711500D03*
X923761Y85550D03*
X928561Y95181D03*
X928428Y83714D03*
X928508Y87747D03*
X928561Y91481D03*
X928457Y79885D03*
X928461Y75981D03*
X916499Y115050D03*
X926999D03*
Y122050D03*
X910999Y124550D03*
X916499Y172550D03*
X922049Y574375D03*
Y978575D03*
X921549Y1788475D03*
X917499Y1796550D03*
X932961Y85581D03*
X943499Y82550D03*
X930999Y115550D03*
X938499D03*
X946899Y122550D03*
X937999Y122050D03*
X934499Y118750D03*
X939549Y175175D03*
X961499Y93350D03*
X958999Y96050D03*
X961499Y100050D03*
X966499Y552050D03*
X965999Y954550D03*
X965150Y1639500D03*
X961702Y1636102D03*
X969600Y1638300D03*
X967600Y1651100D03*
X971558Y1646500D03*
X981200Y1618002D03*
X986400Y1639302D03*
X987100Y1624900D03*
X981200Y1625800D03*
X990425Y1633898D03*
X987029Y1634075D03*
X977500Y1660500D03*
X989502Y1646000D03*
X988800Y1658300D03*
X981500Y1653000D03*
X980800Y1659600D03*
X982050Y1649302D03*
X978000Y1668000D03*
X989000Y1663802D03*
X987200Y1675600D03*
X989900Y1678800D03*
X974000Y1670700D03*
X984211Y1667500D03*
G54D11*
X17600Y5604D03*
X10000Y16500D03*
X11999Y53550D03*
X11499Y34050D03*
X11999Y69050D03*
Y88550D03*
X11499Y106050D03*
X11999Y124550D03*
X11499Y142050D03*
X11999Y177050D03*
Y161550D03*
Y196550D03*
X11499Y214050D03*
X9499Y229050D03*
X8999Y246550D03*
X9499Y281550D03*
Y266050D03*
Y301050D03*
X15499Y328050D03*
X8999Y318550D03*
X15499Y342550D03*
Y360050D03*
X14799Y751450D03*
X8599Y751650D03*
X17299Y773950D03*
X10999Y774050D03*
X8999Y889550D03*
X8499Y907050D03*
X8999Y942050D03*
Y926550D03*
Y961550D03*
X8499Y979050D03*
X8999Y988550D03*
Y1025550D03*
X8499Y1006050D03*
X8999Y1041050D03*
Y1060550D03*
X8499Y1089050D03*
Y1078050D03*
X7999Y1106550D03*
X8499Y1126050D03*
Y1141550D03*
Y1161050D03*
X7999Y1192550D03*
Y1178550D03*
X7499Y1210050D03*
X7999Y1229550D03*
Y1245050D03*
Y1264550D03*
X7499Y1282050D03*
X8299Y1320050D03*
X8799Y1302550D03*
X18099Y1343550D03*
X9399Y1347350D03*
X15299Y1723450D03*
X15399Y1708350D03*
X7099Y1717750D03*
X7199Y1731450D03*
X14899Y1736250D03*
X15299Y1753250D03*
X6099Y1753750D03*
X11299Y1850050D03*
X9099Y1881550D03*
X8499Y1979550D03*
X11500Y1987000D03*
X36000Y5604D03*
X23499Y27050D03*
X40999Y27550D03*
X27799Y38450D03*
X40999Y42050D03*
X25799Y64050D03*
X28399Y94950D03*
X34999Y108550D03*
X41399Y134150D03*
X27999Y131050D03*
Y145550D03*
Y163050D03*
X23999Y243550D03*
Y229050D03*
Y261050D03*
X39999Y327550D03*
Y342050D03*
Y359550D03*
Y576550D03*
X36999Y725050D03*
Y719550D03*
X37499Y714050D03*
X41499Y719550D03*
X26399Y750850D03*
X36499Y740050D03*
Y732550D03*
X39899Y754850D03*
X39399Y768750D03*
X27199Y764950D03*
X28599Y775450D03*
X26799Y874550D03*
X26099Y891650D03*
X25699Y916150D03*
X25099Y942150D03*
X23899Y957950D03*
X24799Y992250D03*
X33899Y1005950D03*
X21499Y1073250D03*
X21399Y1090850D03*
X21299Y1300250D03*
X21799Y1282750D03*
X31499Y1849750D03*
X39399Y1864350D03*
X23999Y1857950D03*
X27199Y1874350D03*
X34799Y1890050D03*
X26500Y1987000D03*
X55700Y5900D03*
X50999Y21150D03*
Y47750D03*
X59499Y90550D03*
Y76050D03*
Y108050D03*
X52499Y130550D03*
Y145050D03*
Y162550D03*
X41699Y183250D03*
X48499Y243050D03*
Y228550D03*
Y260550D03*
X42999Y275650D03*
X51099Y300050D03*
X52199Y342350D03*
X42299Y564150D03*
X62055Y561550D03*
X49555Y563550D03*
X61099Y603236D03*
X52333Y641295D03*
X43499Y657550D03*
X47800Y692800D03*
X53210Y701486D03*
X50999Y720050D03*
X46499Y719550D03*
X51499Y724550D03*
X46499D03*
X41999D03*
X46499Y730550D03*
X41999Y735050D03*
Y731050D03*
X46499Y735050D03*
X41999Y739550D03*
X46499Y739050D03*
X53999Y791000D03*
X52999Y1871550D03*
X57499Y1871050D03*
X45699Y1875550D03*
X47499Y1915050D03*
Y1930550D03*
X62499Y1939550D03*
X58999Y1958050D03*
X61500Y1987500D03*
X44500Y1987000D03*
X55999Y1982550D03*
X73900Y6200D03*
X65499Y27050D03*
Y41550D03*
Y59050D03*
X77165Y110799D03*
X71015Y123666D03*
X78165Y137116D03*
X75299Y261750D03*
X76099Y414250D03*
X75300Y454100D03*
X67300Y450200D03*
X68899Y445450D03*
X66099Y500950D03*
X77165Y514650D03*
X70800Y540300D03*
X75999Y556640D03*
X72599Y578236D03*
X79299Y794150D03*
X67999Y790400D03*
X76399Y820450D03*
X70100Y818900D03*
X77499Y921550D03*
X77002Y952079D03*
X76711Y948089D03*
X77499Y962152D03*
X72799Y982950D03*
X65799Y994050D03*
X67000Y1011500D03*
X77165Y1327335D03*
X77166Y1353400D03*
X76499Y1507050D03*
Y1498050D03*
Y1512050D03*
Y1503050D03*
X76999Y1528050D03*
Y1519050D03*
X81499Y1589050D03*
X83499Y1594050D03*
X78999Y1593550D03*
X74999D03*
X74499Y1602050D03*
Y1598050D03*
X83499D03*
Y1602050D03*
X78999Y1598050D03*
Y1602050D03*
X83599Y1744750D03*
X77165Y1759550D03*
X78529Y1788113D03*
X78999Y1891550D03*
X82999D03*
Y1887550D03*
X78999D03*
X62999Y1914550D03*
X78999Y1896050D03*
X78433Y1900010D03*
X78999Y1904050D03*
X83499Y1896050D03*
X83433Y1904010D03*
X62999Y1926050D03*
X81499Y1915550D03*
X82499Y1957050D03*
X73499D03*
X66499D03*
X73499Y1945550D03*
X79500Y1987500D03*
X65499Y1982550D03*
X73499D03*
X82999D03*
X90900Y5800D03*
X90899Y14850D03*
X96999Y49550D03*
X92999Y52050D03*
X97800Y36000D03*
X96900Y40400D03*
X93000Y44900D03*
X92900Y39700D03*
X95814Y136065D03*
X96184Y151065D03*
Y166065D03*
X97999Y199050D03*
X92899Y231450D03*
X86899Y242750D03*
X93199Y279650D03*
X84899Y289250D03*
X90899Y309550D03*
X94199Y325550D03*
X93499Y337450D03*
X89899Y368350D03*
X95499Y355450D03*
X89999Y396450D03*
X87599Y403950D03*
X95399Y416350D03*
X89099Y426150D03*
X99399Y437450D03*
X93500Y445300D03*
X97699Y449850D03*
X93199D03*
X97999Y445550D03*
X94500Y456800D03*
X100500Y456700D03*
X98999Y488050D03*
X94499Y486550D03*
X93499Y477050D03*
X97699Y481550D03*
Y477050D03*
X93499Y481550D03*
X101500Y536500D03*
X93599Y581236D03*
X93100Y571640D03*
X92599Y606236D03*
X98001Y856950D03*
X97800Y851800D03*
X93808Y852063D03*
X94001Y856895D03*
X97499Y862050D03*
X93299D03*
X93499Y897152D03*
X93900Y882400D03*
X97900D03*
X97700Y887400D03*
X93690Y887139D03*
X97499Y892550D03*
X93499Y892050D03*
X93000Y907165D03*
X83988Y934028D03*
X86700Y982100D03*
X100999Y1101050D03*
X104999D03*
X100999Y1096550D03*
X102999Y1188050D03*
X104999Y1231050D03*
X100999Y1231032D03*
X103499Y1305050D03*
X93316Y1351000D03*
X96000Y1369000D03*
X96100Y1384650D03*
X92499Y1589050D03*
X86999D03*
X90999Y1628550D03*
Y1624550D03*
X91121Y1632549D03*
X86299Y1632550D03*
X85999Y1628550D03*
Y1624550D03*
X84099Y1737150D03*
X93499Y1759550D03*
X94336Y1773113D03*
X104417Y1791480D03*
X97999Y1815050D03*
X104500Y1813400D03*
X83999Y1900050D03*
Y1945050D03*
X98433Y1940510D03*
X98999Y1944550D03*
X102433Y1940555D03*
X103433Y1944510D03*
X92499Y1959050D03*
X101699Y1983850D03*
X98000Y1987500D03*
X91499Y1983050D03*
X107000Y6000D03*
X116400Y56000D03*
X114800Y68500D03*
X123499Y149050D03*
Y140050D03*
X117500Y162300D03*
X124300Y167800D03*
X109499Y410250D03*
X124899Y409050D03*
X126099Y396150D03*
X111299Y425850D03*
X122499Y427900D03*
X108599Y557236D03*
X108900Y587600D03*
X112200Y762200D03*
X112000Y773000D03*
X111299Y821050D03*
X112999Y901150D03*
X106500Y943000D03*
X105300Y960300D03*
X105006Y1096866D03*
X106999Y1114960D03*
X120999Y1188050D03*
X111999D03*
X121657Y1224604D03*
X120999Y1228550D03*
X120499Y1264550D03*
X123938Y1267623D03*
X117149Y1267550D03*
X123500Y1360300D03*
X124999Y1616050D03*
Y1620050D03*
Y1629050D03*
Y1633050D03*
X119999Y1629050D03*
X120100Y1633100D03*
X122499Y1668550D03*
Y1672550D03*
X118999Y1670550D03*
X105749Y1712749D03*
X117499Y1745050D03*
X123499Y1747050D03*
X120299Y1796150D03*
X111499Y1877550D03*
Y1882550D03*
X122999Y1883050D03*
X115999Y1882550D03*
X116499Y1877550D03*
X122999Y1889050D03*
X124433Y1908510D03*
X124999Y1912550D03*
X108499Y1981750D03*
X115000Y1987000D03*
X129100Y55900D03*
X127499Y65050D03*
X141999Y65550D03*
X129999Y78050D03*
X127999Y99550D03*
X133999Y149050D03*
X142999Y141050D03*
X132999Y141550D03*
X144499Y149050D03*
X131799Y201950D03*
X142688Y218861D03*
X143110Y203861D03*
X133000Y240500D03*
X135399Y277050D03*
X130799Y300250D03*
X130099Y326150D03*
X134699Y356050D03*
X139399Y372350D03*
X127999Y425050D03*
Y421050D03*
Y429550D03*
X133499Y445050D03*
X128999Y445550D03*
X130000Y452000D03*
X135999Y472550D03*
X135140Y478930D03*
X139200Y484300D03*
X134499Y488050D03*
X145649Y509550D03*
X136349Y509050D03*
X140499Y499050D03*
X136299D03*
X147300Y526700D03*
X140000Y587700D03*
X140499Y600550D03*
X143999Y605550D03*
X140499Y626050D03*
X131099Y700450D03*
X139099Y707150D03*
X141234Y1029885D03*
X140864Y1044885D03*
X137900Y1103400D03*
X139100Y1097100D03*
X134500Y1108100D03*
X143200Y1116300D03*
X133200Y1132100D03*
X126400Y1138100D03*
X145900Y1163200D03*
X144399Y1171150D03*
X141499Y1185550D03*
X128400Y1188600D03*
X143899Y1196750D03*
X142499Y1205550D03*
X130999Y1198050D03*
X126499Y1264550D03*
X145999Y1353050D03*
X143199Y1412050D03*
X140799Y1435460D03*
X126562Y1670613D03*
X130499Y1730050D03*
X128000Y1735000D03*
X144499Y1729550D03*
X139500Y1730500D03*
X133000Y1734500D03*
X144499Y1745550D03*
X137999Y1747723D03*
X129999Y1747050D03*
X126599Y1789650D03*
X142144Y1801644D03*
X143490Y1855972D03*
X127499Y1889050D03*
X126999Y1882550D03*
X142499Y1905972D03*
X141499Y1895972D03*
X129999Y1908550D03*
X129433Y1912510D03*
X146899Y1961750D03*
X146000Y1987500D03*
X128500D03*
X157299Y5150D03*
X167499Y43550D03*
X156499Y66050D03*
X166999Y88050D03*
X166499Y83550D03*
Y79050D03*
X158499D03*
Y84050D03*
Y88550D03*
Y93550D03*
X166999Y92550D03*
X165499Y106050D03*
X166999Y97050D03*
X152999Y141050D03*
X167499Y149550D03*
X163499Y140050D03*
X160999Y149550D03*
X155999Y181050D03*
X166800Y240800D03*
X158999Y259800D03*
X152808Y246341D03*
X157740Y273924D03*
X167299Y369350D03*
X150699Y411050D03*
X152499Y395950D03*
X149700Y471600D03*
X154100Y476500D03*
X164600Y476700D03*
X153499Y502550D03*
X148999D03*
X147590Y521500D03*
X154099Y529236D03*
X162500Y623400D03*
X152400Y643300D03*
X152124Y651868D03*
X159054Y665400D03*
X161999Y768050D03*
X152499Y810550D03*
Y816050D03*
Y820550D03*
Y825050D03*
X161999Y843550D03*
Y848050D03*
X156499Y846050D03*
X156999Y850050D03*
X156499Y870550D03*
Y876050D03*
X163999Y863050D03*
X159999D03*
X155999Y859050D03*
Y863050D03*
X158114Y883290D03*
X156499Y886950D03*
X159459Y896616D03*
X163499Y896550D03*
X155499Y891050D03*
Y896050D03*
X157499Y904550D03*
Y909050D03*
X151999Y936550D03*
X152499Y931550D03*
X153299Y943750D03*
X159186Y946117D03*
X156499Y985950D03*
X149499Y997650D03*
X162499Y1023550D03*
X158300Y1015000D03*
X163499Y1035050D03*
X159499Y1044579D03*
X151300Y1049300D03*
X165600Y1057428D03*
X168099Y1083550D03*
X164999Y1075550D03*
X159055Y1070400D03*
X167999Y1092850D03*
X167499Y1118550D03*
X167999Y1130550D03*
X163499Y1171650D03*
X151699Y1158550D03*
X151499Y1173050D03*
X150999Y1181150D03*
X167499Y1389050D03*
X156999Y1397750D03*
X166799Y1409350D03*
X157915Y1420460D03*
X163499Y1433350D03*
X165499Y1453550D03*
X166799Y1487450D03*
X159054Y1476200D03*
X167499Y1714113D03*
X162499D03*
X165499Y1730613D03*
X167999Y1726613D03*
X163499D03*
X157500Y1797400D03*
X158000Y1825400D03*
X157999Y1840972D03*
X167200Y1868000D03*
X159054Y1855050D03*
X163599Y1892050D03*
X168299Y1879850D03*
X159054Y1881800D03*
X159173Y1935972D03*
X148499Y1977250D03*
X163500Y1987500D03*
X189499Y4550D03*
X183499Y45550D03*
X168499Y65550D03*
X169999Y103050D03*
X176499Y140050D03*
X177899Y199250D03*
X185999Y250550D03*
X181299Y267350D03*
X187199Y359050D03*
X181599Y396250D03*
X168999Y413050D03*
X188499Y413550D03*
X171300Y476700D03*
X187499Y531613D03*
Y536113D03*
X188999Y541113D03*
Y549613D03*
Y545613D03*
X181999Y624050D03*
Y609550D03*
Y641550D03*
X182599Y688350D03*
X171999Y672450D03*
X170799Y689150D03*
X178899Y765250D03*
X172599Y774250D03*
X168499Y846713D03*
X173899Y846550D03*
X172099Y877450D03*
X169299Y956350D03*
X171499Y998650D03*
X169299Y1067150D03*
X171599Y1139950D03*
X180400Y1202800D03*
X181700Y1219900D03*
X179800Y1244100D03*
X179500Y1262000D03*
X175823Y1297070D03*
X179999Y1301550D03*
Y1292550D03*
X175499D03*
X179999Y1296613D03*
X175499Y1302113D03*
X179999Y1306050D03*
X175499Y1306113D03*
X178200Y1393400D03*
X180599Y1424050D03*
X180000Y1439500D03*
X176599Y1447450D03*
X172299Y1465850D03*
X181500Y1479000D03*
X176299Y1500150D03*
X181900Y1675300D03*
X180701Y1716050D03*
X179701Y1724550D03*
X172499Y1714050D03*
X180000Y1731000D03*
X170499Y1731050D03*
X172499Y1726613D03*
X185999Y1746050D03*
X182299Y1801350D03*
X173899Y1813250D03*
X177599Y1866750D03*
X168499Y1855550D03*
X181099Y1885850D03*
X168699Y1957150D03*
X183999Y1968150D03*
X188199Y1978250D03*
X183000Y1987500D03*
X206999Y5050D03*
X191999Y68050D03*
X192499Y57550D03*
X206899Y171650D03*
X190199Y178650D03*
X191999Y221550D03*
X203499Y250550D03*
X201199Y266750D03*
X209199Y365050D03*
X209499Y412550D03*
X209999Y426150D03*
X194999Y490050D03*
X190499Y487550D03*
X191199Y491550D03*
X205300Y508100D03*
X190499Y507513D03*
X193499Y541113D03*
Y549613D03*
X193999Y545550D03*
X206499Y623550D03*
Y609050D03*
X207300Y639400D03*
X199199Y659150D03*
X190399Y689050D03*
X209500Y759000D03*
X208799Y766750D03*
X190699Y778350D03*
X197099Y795050D03*
X208299Y805350D03*
X202900Y811900D03*
X198199Y805950D03*
X198499Y884113D03*
X204699Y929450D03*
X206699Y953050D03*
X203999Y943350D03*
X205999Y978250D03*
X206299Y990250D03*
X207299Y1008150D03*
X202100Y1028100D03*
X199499Y1093850D03*
X209900Y1093600D03*
X208199Y1145850D03*
X210199Y1173450D03*
X204199Y1163850D03*
X201600Y1205900D03*
X196499Y1215550D03*
Y1196550D03*
X196399Y1236650D03*
X196499Y1224550D03*
X195499Y1251050D03*
X202199Y1276850D03*
X195499Y1279050D03*
Y1270050D03*
X202899Y1291450D03*
X207699Y1337950D03*
X195500Y1352500D03*
X208049Y1385550D03*
X203199Y1393250D03*
X204699Y1418350D03*
X201000Y1408500D03*
X194200Y1457900D03*
X204999Y1472650D03*
X208999Y1491250D03*
X202399Y1500750D03*
X209200Y1624000D03*
X200600Y1663600D03*
X199900Y1670600D03*
X193499Y1674050D03*
X197600Y1694900D03*
X204400Y1688200D03*
X209901Y1691850D03*
X201801Y1701450D03*
X195001Y1708150D03*
X205200Y1708000D03*
X195500Y1717000D03*
X195000Y1725500D03*
X206900Y1726700D03*
X199699Y1761450D03*
X205199Y1801950D03*
X209999Y1825050D03*
X192100Y1813500D03*
X204399Y1855450D03*
X206999Y1867550D03*
X207199Y1892850D03*
X191599Y1891550D03*
X199599Y1879850D03*
X205499Y1968650D03*
X190199Y1957650D03*
X199600Y1974900D03*
X209699Y1978750D03*
X199000Y1987500D03*
X226499Y5050D03*
X225499Y52550D03*
Y46550D03*
Y63550D03*
Y58050D03*
X229099Y161350D03*
X227999Y178050D03*
X227499Y192050D03*
X227999Y187050D03*
Y182550D03*
X210999Y221550D03*
X217999Y250550D03*
X223799Y365350D03*
X217599Y396450D03*
X218499Y474850D03*
X224299Y494650D03*
X220499Y560050D03*
Y545550D03*
Y577550D03*
X224999Y613450D03*
X219999Y632550D03*
Y647050D03*
X226399Y677550D03*
X212999Y677350D03*
X218800Y668700D03*
X224099Y770250D03*
X214799Y774750D03*
X227199Y795050D03*
X217300Y816800D03*
X215999Y887550D03*
X220499D03*
X215499Y883550D03*
X219499Y939613D03*
X214999D03*
X219499Y926613D03*
X214999D03*
X225299Y957650D03*
X213999Y958650D03*
X219499Y948613D03*
Y943813D03*
X214999Y944113D03*
Y948613D03*
X217499Y981050D03*
X216999Y967550D03*
X217499Y998550D03*
X217999Y1012050D03*
X215999Y1039550D03*
X216499Y1053050D03*
X214499Y1154250D03*
X223099Y1182750D03*
X212499Y1184550D03*
Y1212550D03*
X221599Y1237250D03*
X220999Y1224350D03*
X222299Y1251850D03*
X229899Y1250550D03*
X211499Y1258050D03*
Y1239050D03*
X216300Y1274800D03*
X211499Y1267050D03*
X219099Y1325950D03*
X226599Y1340250D03*
X213199Y1350050D03*
X227399Y1363050D03*
X217499Y1387450D03*
X230599Y1400250D03*
X217999Y1408850D03*
X227999Y1421550D03*
X226300Y1447800D03*
X230899Y1437350D03*
X212400Y1433700D03*
X213399Y1500300D03*
X212899Y1535550D03*
X230999D03*
X211999Y1568550D03*
X231499Y1575050D03*
X224499D03*
X217999Y1574550D03*
X211999D03*
X218000Y1614300D03*
X228999Y1637550D03*
X211999Y1653550D03*
X230600Y1670500D03*
X213000Y1672500D03*
X216601Y1684350D03*
X226800Y1684200D03*
X220100Y1691700D03*
X212000Y1701300D03*
X222700Y1710100D03*
X222499Y1743850D03*
X221499Y1760950D03*
X220799Y1791550D03*
X215299Y1813950D03*
X224800Y1867000D03*
X228999Y1856050D03*
X212399Y1885850D03*
X226999Y1941050D03*
X227499Y1971050D03*
X221300Y1971200D03*
X225199Y1978750D03*
X216999Y1987550D03*
X241999Y5050D03*
X247499Y37550D03*
X246999Y46550D03*
Y56050D03*
X247499Y65050D03*
X244499Y136550D03*
Y122050D03*
X244900Y149100D03*
X231999Y178050D03*
Y192050D03*
Y187050D03*
Y182550D03*
X232400Y220700D03*
X249800Y248800D03*
X235399Y263350D03*
X237699Y426050D03*
X232999Y414550D03*
X252499Y415050D03*
X251499Y446050D03*
X231999Y445550D03*
X251999Y462050D03*
X232499Y461550D03*
X244199Y483350D03*
X242099Y511750D03*
X244999Y559550D03*
Y545050D03*
Y577050D03*
X244499Y632050D03*
X246500Y663300D03*
X245000Y647000D03*
X234200Y668300D03*
X245599Y773450D03*
X234299Y773750D03*
X247099Y795050D03*
X233799Y806350D03*
X245399Y823550D03*
X244099Y857450D03*
X252399Y838250D03*
X245199Y878050D03*
X232399Y886550D03*
X252899Y886350D03*
X245399Y907450D03*
X243899Y923650D03*
X242199Y938750D03*
X252499Y948850D03*
X244199Y973250D03*
X232299Y981950D03*
X233499Y966050D03*
X245899Y995250D03*
X233999Y997050D03*
Y1012550D03*
X232499Y1038050D03*
X249499Y1104150D03*
X232599Y1195750D03*
X251999Y1184550D03*
X242199Y1210050D03*
X242599Y1198350D03*
X247899Y1208650D03*
X234299Y1232650D03*
X250900Y1248500D03*
X242900Y1263000D03*
X232799Y1276150D03*
X241399Y1303250D03*
X239099Y1314150D03*
X252399Y1326350D03*
X245999Y1339050D03*
Y1358050D03*
X234300Y1375700D03*
X246499Y1370050D03*
X249800Y1388400D03*
X244999Y1412550D03*
X245499Y1424550D03*
X238899Y1453750D03*
X248000Y1482000D03*
X250199Y1473550D03*
X247500Y1499000D03*
X236999Y1535550D03*
X238300Y1575100D03*
X246200Y1617600D03*
X239400Y1624300D03*
X242999Y1658050D03*
X237400Y1663800D03*
X235499Y1697050D03*
X249199Y1743150D03*
X237999Y1730550D03*
X244999Y1755050D03*
X252199Y1793050D03*
X238699Y1801850D03*
X241199Y1867150D03*
X244700Y1878700D03*
X241255Y1896055D03*
X238999Y1970550D03*
X232999Y1971050D03*
X240900Y1979000D03*
X236500Y1987500D03*
X261499Y4550D03*
X253999Y48050D03*
X264999Y55350D03*
X261299Y75950D03*
X258699Y104550D03*
X265299Y96250D03*
X262299Y164050D03*
X262699Y208550D03*
X271999Y216050D03*
X265999Y245050D03*
X267498Y305114D03*
Y300114D03*
Y295114D03*
Y310114D03*
X258999Y396650D03*
X266699Y425050D03*
X269999Y415050D03*
X272499Y445050D03*
X266199Y472350D03*
X272999Y461050D03*
X257499Y498050D03*
Y512550D03*
Y530050D03*
X256499Y577050D03*
Y591550D03*
Y609050D03*
X269499Y616550D03*
X257199Y640050D03*
X269499Y631050D03*
Y648550D03*
X268499Y701550D03*
Y706550D03*
Y716550D03*
Y711550D03*
X268099Y795450D03*
X254699Y807650D03*
X264499Y829050D03*
X264999Y842550D03*
Y858450D03*
X265799Y901850D03*
X256199Y916250D03*
X254899Y929250D03*
X253499Y938050D03*
X269599Y923950D03*
X267199Y935350D03*
X264799Y946850D03*
X263299Y959350D03*
X272999Y981050D03*
Y965550D03*
X256499Y967050D03*
X262499Y995850D03*
X254499Y984550D03*
X258999Y1011550D03*
X269999Y1037050D03*
X253499Y1038550D03*
X269999Y1052550D03*
X253999Y1052050D03*
X272999Y1102850D03*
X262499Y1129150D03*
X260349Y1139200D03*
X272499Y1153050D03*
X268499D03*
X263999D03*
X259999Y1152992D03*
X271999Y1161550D03*
X267999D03*
X263499D03*
X259499D03*
X272999Y1214150D03*
X261199Y1227950D03*
X264800Y1261300D03*
X254899Y1289950D03*
X264799Y1313850D03*
X265299Y1339650D03*
X263699Y1359550D03*
X265499Y1376950D03*
X258999Y1396950D03*
X270599Y1408550D03*
X259299Y1438750D03*
X268499Y1453550D03*
X260999Y1503550D03*
X266999Y1512550D03*
X267349Y1518150D03*
Y1522550D03*
Y1527172D03*
X265700Y1635100D03*
X258700Y1645100D03*
X270999Y1660550D03*
X253999Y1676550D03*
X273499Y1694050D03*
X255699Y1722550D03*
X256499Y1710050D03*
X263499Y1734550D03*
X270599Y1748950D03*
X259499Y1760650D03*
X270599Y1801450D03*
X253899Y1813250D03*
X261499Y1825050D03*
X255999Y1855950D03*
X270299Y1867250D03*
X266999Y1915550D03*
Y1920050D03*
Y1924550D03*
Y1929050D03*
Y1933550D03*
X254500Y1987500D03*
X272000D03*
X278999Y5050D03*
X292999Y4550D03*
X294100Y28000D03*
X289499Y39050D03*
X286603Y34928D03*
X289999Y72550D03*
X290999Y67550D03*
X288499Y76550D03*
X289499Y80550D03*
X283599Y106250D03*
X274700Y131500D03*
X280999Y120050D03*
Y152050D03*
X290999Y216050D03*
X283499Y245050D03*
X279998Y304114D03*
Y299614D03*
Y295114D03*
Y308614D03*
X277799Y338599D03*
X276299Y376050D03*
X289399Y395750D03*
X284499Y415050D03*
X291599Y446150D03*
X286999Y462050D03*
X281999Y497550D03*
X292999Y483550D03*
X281999Y512050D03*
Y529550D03*
X277999Y545350D03*
X280999Y576550D03*
Y591050D03*
Y608550D03*
X293999Y616050D03*
Y630550D03*
Y648050D03*
X280999Y701550D03*
Y705550D03*
Y717550D03*
X280433Y713590D03*
X287799Y794850D03*
X275299Y806350D03*
X288899Y820550D03*
X280999Y827550D03*
X283599Y857450D03*
X293899Y843850D03*
X280999Y843050D03*
Y870050D03*
X281499Y883550D03*
X274299Y912950D03*
X287299Y901050D03*
X281099Y943550D03*
X278799Y956150D03*
X290099Y948650D03*
X289399Y963350D03*
X277599Y975250D03*
X288099Y971250D03*
X285399Y982950D03*
X294699Y989550D03*
X287099Y1000150D03*
X274999Y996550D03*
X289699Y1021750D03*
X275099Y1024750D03*
X274999Y1012050D03*
X287099Y1035050D03*
X282999Y1099550D03*
X274900Y1115600D03*
X290699Y1122650D03*
X283499Y1113050D03*
X276299Y1134550D03*
X283299Y1144850D03*
X291399Y1174150D03*
X279799Y1191750D03*
X286599Y1203750D03*
X283799Y1249250D03*
X274299Y1276450D03*
X281099Y1302850D03*
X286799Y1326450D03*
X286499Y1364050D03*
Y1345050D03*
X278799Y1386250D03*
X285499Y1399550D03*
X278000Y1422000D03*
X285499Y1418550D03*
Y1427550D03*
X286600Y1449700D03*
X279499Y1510550D03*
X286700Y1516100D03*
X279499Y1515050D03*
X279075Y1525957D03*
X278567Y1529925D03*
X278499Y1621550D03*
X289000Y1641800D03*
X284300Y1676900D03*
X291099Y1707450D03*
X280499Y1718550D03*
X285499Y1742550D03*
X290699Y1760750D03*
X286599Y1791850D03*
X284299Y1811150D03*
X295299Y1870250D03*
X283999Y1856050D03*
X293999Y1933050D03*
X281999Y1918550D03*
Y1923550D03*
Y1928550D03*
X291499Y1987550D03*
X310499Y5050D03*
X304500Y44500D03*
X303300Y39500D03*
X308700Y39800D03*
X308800Y46400D03*
X306999Y55450D03*
X311299D03*
X315799Y55350D03*
X308499Y72550D03*
X303999Y74050D03*
X307999Y78550D03*
X306100Y126500D03*
X307199Y205550D03*
X310499Y216550D03*
X297999Y245050D03*
X313199Y270350D03*
X313000Y313900D03*
X299899Y376650D03*
X310999Y396250D03*
X300899Y431850D03*
X303999Y415550D03*
X306100Y462000D03*
X312499Y484050D03*
X298599Y501250D03*
X309399Y513450D03*
X297599Y519350D03*
X307499Y555550D03*
Y541050D03*
X297499Y551050D03*
X296199Y568550D03*
X307499Y573050D03*
X302899Y607950D03*
X307499Y661550D03*
Y647050D03*
X297699Y681850D03*
X307499Y679050D03*
X308899Y705150D03*
X298399Y703450D03*
X296399Y716950D03*
X314499Y754550D03*
X307999Y803150D03*
X307899Y794550D03*
X300199Y835250D03*
X304899Y856150D03*
X313499Y847850D03*
X315199Y869450D03*
X297499Y868550D03*
X302499Y899050D03*
X297499Y884050D03*
X302199Y914650D03*
X315199Y925950D03*
X310699Y943550D03*
X299399Y965950D03*
X298099Y977250D03*
X307999Y970650D03*
X306699Y981250D03*
X304399Y997550D03*
X298399Y1008150D03*
X306399Y1020750D03*
X303699Y1038050D03*
X299999Y1052350D03*
X304699Y1057050D03*
X312299Y1093550D03*
X299499Y1098050D03*
Y1113550D03*
X316499Y1124550D03*
X307999Y1142050D03*
X304499Y1156650D03*
X313499Y1170150D03*
X300699Y1185150D03*
X315408Y1202663D03*
X311999Y1213850D03*
X300699Y1227350D03*
X310299Y1240050D03*
X304699Y1265850D03*
X312499Y1280350D03*
X295399Y1292950D03*
X300499Y1305350D03*
X311500Y1316300D03*
X297899Y1336150D03*
X298099Y1357250D03*
X311900Y1344900D03*
X301699Y1377950D03*
X312900Y1366900D03*
X301699Y1395750D03*
X313600Y1391300D03*
X303499Y1411250D03*
X312100Y1420700D03*
X300899Y1433350D03*
X313600Y1442700D03*
X304699Y1457550D03*
X312800Y1467400D03*
X296599Y1497150D03*
X312000Y1514600D03*
X307000Y1619600D03*
X302399Y1662950D03*
X299999Y1696050D03*
X303999Y1722050D03*
X297099Y1733850D03*
X303499Y1753550D03*
X303999Y1800850D03*
X315499Y1812250D03*
X298999Y1855950D03*
X313599Y1870250D03*
X308099Y1880550D03*
X313599Y1889250D03*
X314099Y1901250D03*
X305999Y1913050D03*
X306999Y1932550D03*
X302499D03*
X298499D03*
X302499Y1922050D03*
X296858Y1956228D03*
X311500Y1987500D03*
X329999Y5050D03*
X332200Y94200D03*
X321799Y173950D03*
X317499Y192950D03*
X331499Y193250D03*
X325499Y249450D03*
X337499Y282550D03*
X316999Y312576D03*
X321748Y343299D03*
X328799Y372350D03*
X336099Y417550D03*
X322099Y426850D03*
X324999Y414550D03*
X328599Y442250D03*
X327900Y463200D03*
X333499Y483050D03*
X329999Y510450D03*
X321999Y533150D03*
X331999Y555050D03*
Y540550D03*
X321999Y550550D03*
X321299Y565250D03*
X320799Y582050D03*
X331999Y572550D03*
X328599Y602450D03*
X328499Y635650D03*
X317999Y627850D03*
X331999Y661050D03*
Y646550D03*
Y678550D03*
X324599Y696150D03*
X330799Y712450D03*
X318999Y814350D03*
X325599Y823950D03*
X330299Y871850D03*
X323799Y859850D03*
X321099Y899650D03*
X323099Y885050D03*
X322099Y913650D03*
X331099Y923650D03*
X328099Y937250D03*
X323499Y956950D03*
X329799Y970650D03*
X333099Y983450D03*
X320999Y997250D03*
X331299Y1017150D03*
X321299Y1012450D03*
Y1024750D03*
X331599Y1028750D03*
X329599Y1040750D03*
X318299Y1038750D03*
X329599Y1057050D03*
X319999Y1066950D03*
X317699Y1054650D03*
X329299Y1098550D03*
X326599Y1112350D03*
X332999Y1123050D03*
X323999Y1153250D03*
X332999Y1138550D03*
X317999Y1137550D03*
X329799Y1182750D03*
X328999Y1200550D03*
X326649Y1227850D03*
Y1218850D03*
X327999Y1255050D03*
X333349Y1270500D03*
Y1288900D03*
Y1307000D03*
Y1332800D03*
Y1363500D03*
Y1393100D03*
Y1429500D03*
Y1481900D03*
X332500Y1519700D03*
X337199Y1636350D03*
X320299Y1642950D03*
X316799Y1657450D03*
X335767Y1662735D03*
X318499Y1675550D03*
X334399Y1691650D03*
X329999Y1716950D03*
X320999Y1706050D03*
X321999Y1733050D03*
X326301Y1766030D03*
X321499Y1772550D03*
X327299Y1791850D03*
X322299Y1802150D03*
X334999Y1797050D03*
X337499Y1855950D03*
X316999D03*
X336799Y1869950D03*
X326399Y1876250D03*
X336799Y1888950D03*
X326899Y1907250D03*
X326399Y1895250D03*
X336799Y1897950D03*
X335799Y1916450D03*
X326799Y1977050D03*
X329999Y1987550D03*
X345499Y5050D03*
X356499Y113050D03*
X351999D03*
X347499D03*
X355999Y100550D03*
X350999D03*
X345999D03*
X354099Y175350D03*
X343399Y161350D03*
X343999Y190050D03*
X343799Y204550D03*
X355499Y219050D03*
X337999D03*
X355999Y242750D03*
X343499Y253550D03*
X347699Y269050D03*
X354999Y282550D03*
X347399Y301950D03*
X339399Y358050D03*
X357999Y359050D03*
X354099Y373050D03*
X338399Y395650D03*
X338899Y433850D03*
X354699Y426650D03*
X356399Y451750D03*
X351399Y470750D03*
X340799Y512050D03*
X358399Y498650D03*
X341399Y535850D03*
X357399Y521250D03*
Y530550D03*
X341399Y558950D03*
X357399Y543850D03*
X357999Y559450D03*
X340299Y586550D03*
X342199Y613050D03*
X342099Y646350D03*
X341899Y664950D03*
X342599Y678850D03*
X345399Y698950D03*
X357699Y707750D03*
X341399Y715050D03*
X355999Y752850D03*
X353999Y787750D03*
X347699Y773450D03*
X338099Y811650D03*
X338599Y821650D03*
Y840450D03*
X340099Y887350D03*
X338399Y901050D03*
X340099Y910350D03*
X340399Y931250D03*
X340099Y952850D03*
X339599Y1081550D03*
X344399Y1338150D03*
X343599Y1360050D03*
X344099Y1393750D03*
Y1421150D03*
Y1449550D03*
X351899Y1570850D03*
X344500Y1583600D03*
X350600Y1610900D03*
X349099Y1634550D03*
X351099Y1691150D03*
X352000Y1700400D03*
X343899Y1752650D03*
X357999Y1796050D03*
X355699Y1810750D03*
X351999Y1855450D03*
X348999Y1879050D03*
X349499Y1910050D03*
X348999Y1898050D03*
X347999Y1925550D03*
X348499Y1956550D03*
X347999Y1944550D03*
X347699Y1972250D03*
X345499Y1987550D03*
X364999Y4550D03*
X376999Y65550D03*
Y70050D03*
X360999Y113050D03*
Y100550D03*
X363999Y136050D03*
Y121550D03*
Y153550D03*
X362999Y190050D03*
X369999Y219050D03*
X362499Y253550D03*
X369499Y282550D03*
X359399Y307250D03*
X368299Y386350D03*
X359399Y576050D03*
Y599650D03*
X360399Y615550D03*
X359699Y627550D03*
X358899Y657150D03*
X359399Y669450D03*
X359199Y690650D03*
X377499Y1182050D03*
Y1210050D03*
Y1201050D03*
X376499Y1236550D03*
Y1255550D03*
Y1264550D03*
X376599Y1293950D03*
X375599Y1323350D03*
X374499Y1347550D03*
Y1375550D03*
Y1366550D03*
X373499Y1402050D03*
Y1421050D03*
X376299Y1437650D03*
X373499Y1430050D03*
X373099Y1456550D03*
X374799Y1491250D03*
X374099Y1554550D03*
X376099Y1572850D03*
X375099Y1608250D03*
X377700Y1629000D03*
X374999Y1656750D03*
X377099Y1696350D03*
X359499Y1736850D03*
X376799Y1734050D03*
X376499Y1775550D03*
X369499Y1855950D03*
X359999Y1878550D03*
X369799Y1880050D03*
X359999Y1897550D03*
Y1906550D03*
X369999Y1901950D03*
X358999Y1925050D03*
X369199Y1919750D03*
X367299Y1956950D03*
X367999Y1940250D03*
X367299Y1972950D03*
X364999Y1987050D03*
X382499Y5050D03*
X395999Y5550D03*
X381499Y65550D03*
Y70050D03*
X389599Y90950D03*
X380599Y103550D03*
X381299Y136750D03*
X400499Y134050D03*
Y119550D03*
Y151550D03*
X389299Y161650D03*
X382499Y190550D03*
X387599Y220150D03*
X385999Y207250D03*
X381999Y254050D03*
X382999Y276650D03*
X386899Y299250D03*
X383299Y310250D03*
X386599Y348450D03*
X394899Y357750D03*
X380599Y381050D03*
X380099Y1709650D03*
X393499Y1759550D03*
X393999Y1784550D03*
X387899Y1802850D03*
X391499Y1855950D03*
X389499Y1885050D03*
Y1913050D03*
Y1904050D03*
X388499Y1932950D03*
Y1950550D03*
X385099Y1975950D03*
X399299Y1976750D03*
X388499Y1959550D03*
X382499Y1987550D03*
X413499Y6050D03*
X416999Y25050D03*
X417499Y46550D03*
X416999Y63550D03*
X417499Y79050D03*
Y93550D03*
Y108050D03*
Y125550D03*
X416999Y145050D03*
Y164050D03*
X417999Y185050D03*
X412999Y275550D03*
Y307550D03*
Y290050D03*
X422199Y363350D03*
X420199Y391350D03*
X415099Y422550D03*
X410799Y431150D03*
X419599Y458550D03*
X415999Y518550D03*
X420199Y638550D03*
X418799Y877050D03*
Y896050D03*
X409499Y1102550D03*
X419999Y1115550D03*
X415499Y1161550D03*
X416099Y1183550D03*
X415499Y1176050D03*
X419499Y1234050D03*
Y1219550D03*
X420099Y1241550D03*
X416699Y1342650D03*
X416199Y1367550D03*
X414799Y1532350D03*
X418299Y1561250D03*
X415999Y1603250D03*
X416199Y1625250D03*
X414799Y1653750D03*
X414399Y1678350D03*
X414499Y1707250D03*
X410757Y1772872D03*
X417799Y1790850D03*
X414499Y1810450D03*
X406999Y1855950D03*
X421399Y1888050D03*
X406499Y1893050D03*
Y1874050D03*
X421399Y1907050D03*
X406999Y1905050D03*
X420399Y1934550D03*
X421399Y1916050D03*
X405499Y1920550D03*
X420399Y1953550D03*
X405999Y1951550D03*
X405499Y1939550D03*
X420399Y1962550D03*
X420799Y1977250D03*
X420500Y1987000D03*
X403500D03*
X432999Y6050D03*
X436499Y31350D03*
Y50350D03*
X437499Y71350D03*
X441799Y102450D03*
Y121450D03*
X442799Y142450D03*
X430499Y217050D03*
X423799Y259750D03*
X437499Y275050D03*
Y307050D03*
Y289550D03*
X422499Y348150D03*
X438999Y381550D03*
X426599Y415350D03*
X443199Y440850D03*
X440099Y459250D03*
X431099Y479350D03*
X435499Y519050D03*
X430099Y551450D03*
X427999Y580050D03*
Y565550D03*
Y597550D03*
X427499Y624550D03*
X437299Y744650D03*
X435299Y763150D03*
X424999Y766550D03*
X435299Y777650D03*
X422999Y785050D03*
X434799Y814650D03*
X435299Y795150D03*
X422999Y799550D03*
X434799Y833650D03*
X422999Y817050D03*
X422499Y855550D03*
Y836550D03*
X442599Y905650D03*
Y924650D03*
X423299Y994050D03*
Y1013050D03*
X424299Y1034050D03*
X432599Y1064550D03*
X433599Y1085550D03*
X428999Y1102550D03*
X439499Y1115550D03*
X436999Y1128050D03*
X437599Y1150050D03*
X436999Y1142550D03*
X443199Y1224250D03*
Y1238750D03*
X424999Y1278550D03*
Y1259550D03*
X425499Y1290550D03*
X428499Y1325350D03*
X434499Y1360250D03*
X422299Y1394950D03*
X441499Y1399550D03*
X426799Y1416050D03*
X441499Y1414050D03*
X423299Y1430350D03*
X425799Y1447950D03*
X441499Y1431550D03*
X427099Y1469150D03*
X424299Y1541350D03*
X439599Y1552150D03*
X434500Y1579500D03*
X432499Y1617550D03*
X431999Y1605550D03*
X425499Y1635050D03*
X432400Y1680100D03*
X427499Y1662050D03*
X428600Y1691200D03*
X435300Y1715300D03*
X429499Y1748050D03*
X441499Y1758050D03*
X436799Y1772550D03*
X422999Y1778550D03*
X426499Y1855450D03*
X434299Y1876050D03*
Y1904050D03*
Y1895050D03*
X433299Y1922550D03*
Y1950550D03*
Y1941550D03*
X436299Y1977250D03*
X438999Y1987550D03*
X448499Y6050D03*
X445799Y165650D03*
Y184650D03*
X446799Y205650D03*
X449999Y217050D03*
X448999Y255550D03*
X444499Y283050D03*
X463999Y283550D03*
X443499Y354050D03*
X464499Y353050D03*
X458499Y382050D03*
X450300Y404200D03*
X453999Y417550D03*
X454999Y438550D03*
X454499Y472550D03*
Y458050D03*
Y490050D03*
X456499Y518050D03*
X453999Y509550D03*
X452499Y579550D03*
Y565050D03*
Y597050D03*
X463999Y659550D03*
X450399Y672750D03*
X444799Y687350D03*
X463999Y674050D03*
Y691550D03*
X451099Y711650D03*
X452099Y762450D03*
Y781450D03*
X453399Y807950D03*
Y826950D03*
X462999Y865050D03*
Y884050D03*
X464499Y896050D03*
X462499Y914550D03*
Y929050D03*
X443599Y945650D03*
X462499Y946550D03*
X461999Y966050D03*
Y985050D03*
X462499Y1043850D03*
Y1062850D03*
X463499Y1083850D03*
X463999Y1102050D03*
X444499Y1102550D03*
X454999Y1115550D03*
X453499Y1140550D03*
X454499Y1161550D03*
X443799Y1246250D03*
Y1274250D03*
Y1265250D03*
X448099Y1341250D03*
X444899Y1377950D03*
X464199Y1401450D03*
X459999Y1424050D03*
X456399Y1445950D03*
X459699Y1468050D03*
X445099Y1464250D03*
X444299Y1532650D03*
X461399Y1541650D03*
X452199Y1550650D03*
X449199Y1579050D03*
X443799Y1612250D03*
X460199Y1632850D03*
X449599Y1656950D03*
X448399Y1699450D03*
X447699Y1682850D03*
X458499Y1742050D03*
X463999Y1772050D03*
X445499Y1792550D03*
X448099Y1809450D03*
X443999Y1855950D03*
X460299Y1892350D03*
X446999Y1880050D03*
X460299Y1911350D03*
X446999Y1908050D03*
Y1899050D03*
X460299Y1920350D03*
X445999Y1926550D03*
X459299Y1938850D03*
X445999Y1954550D03*
Y1945550D03*
X459299Y1966850D03*
Y1957850D03*
X455799Y1976750D03*
X456500Y1987500D03*
X467999Y5550D03*
X485499Y6050D03*
X465799Y24750D03*
Y43750D03*
X466799Y64750D03*
X470399Y84550D03*
Y103550D03*
X471399Y124550D03*
X473099Y141050D03*
X483599Y179350D03*
X473099Y160050D03*
X474099Y181050D03*
X472999Y214550D03*
X469999Y254550D03*
X481499Y283550D03*
X466399Y304950D03*
X479299Y297250D03*
X483499Y353050D03*
X485000Y373200D03*
X484900Y394700D03*
X468799Y414250D03*
X472499Y458050D03*
X471499Y493950D03*
X485299Y534550D03*
X479999Y581050D03*
Y566550D03*
Y598550D03*
X472999Y736550D03*
X467699Y772750D03*
X468699Y788350D03*
X479599Y847550D03*
X475699Y880450D03*
X483499Y1064850D03*
X484499Y1085850D03*
X481499Y1102550D03*
X474499Y1115050D03*
X473099Y1144550D03*
X474099Y1165550D03*
X465499Y1265550D03*
Y1284550D03*
Y1293550D03*
X468999Y1323950D03*
X473999Y1342450D03*
X468699Y1362850D03*
X485599Y1367550D03*
X466699Y1378150D03*
X481499Y1402550D03*
Y1417050D03*
X482599Y1449950D03*
X478299Y1464850D03*
X466999Y1530650D03*
X474299Y1544750D03*
X472299Y1572050D03*
X484200Y1579900D03*
X465999Y1603450D03*
X472499Y1611550D03*
X484999Y1636550D03*
X472499Y1620550D03*
X483599Y1662550D03*
X467999Y1668050D03*
X485599Y1694850D03*
X467999Y1687050D03*
Y1696050D03*
X468499Y1712550D03*
X480999Y1756050D03*
X484999Y1779050D03*
X472699Y1792150D03*
X481299Y1811150D03*
X480499Y1855450D03*
X464999D03*
X476199Y1877450D03*
Y1905450D03*
Y1896450D03*
X475199Y1923950D03*
Y1951950D03*
Y1942950D03*
X473299Y1977250D03*
X476000Y1987000D03*
X498999Y6050D03*
X499999Y25550D03*
X500499Y47050D03*
X499999Y64050D03*
X500499Y79550D03*
Y94050D03*
Y108550D03*
Y126050D03*
X499999Y145550D03*
Y164550D03*
X504199Y193250D03*
X502899Y217150D03*
X488999Y254550D03*
X495999Y283550D03*
X502999Y353550D03*
X490999Y412550D03*
X503699Y419250D03*
X490999Y427050D03*
Y444550D03*
X498399Y470050D03*
X490499Y464050D03*
Y483050D03*
X491499Y504050D03*
X504499Y580550D03*
Y566050D03*
Y598050D03*
X488499Y659050D03*
Y673550D03*
Y691050D03*
X506599Y711650D03*
X487299Y716950D03*
X490299Y734550D03*
X489599Y752450D03*
X495999Y795050D03*
X493999Y813550D03*
Y828050D03*
Y845550D03*
X493499Y865050D03*
Y884050D03*
X485799Y920050D03*
Y901050D03*
X486799Y941050D03*
X493099Y996350D03*
X494099Y1017350D03*
X501499Y1102550D03*
X491999Y1115550D03*
X504399Y1132250D03*
X505399Y1153250D03*
X486499Y1210550D03*
Y1196050D03*
X506599Y1202350D03*
Y1216850D03*
X487099Y1218050D03*
X498299Y1323350D03*
X499199Y1350550D03*
X498899Y1386450D03*
Y1408350D03*
X500899Y1434350D03*
X505899Y1466250D03*
X488299Y1531050D03*
X499699Y1538950D03*
X502199Y1566250D03*
X487099Y1606250D03*
X501399Y1634550D03*
X502899Y1709650D03*
X496999Y1799550D03*
X499999Y1854950D03*
X505799Y1893050D03*
X492999Y1878050D03*
X505799Y1912050D03*
X493499Y1909050D03*
X492999Y1897050D03*
X505799Y1921050D03*
X491999Y1924550D03*
X504799Y1939550D03*
X492499Y1955550D03*
X491999Y1943550D03*
X504799Y1967550D03*
Y1958550D03*
X493799Y1977250D03*
X492500Y1987500D03*
X516499Y6550D03*
X522899Y45350D03*
Y64350D03*
X523899Y85350D03*
X520299Y122450D03*
Y141450D03*
X521299Y162450D03*
X508499Y255050D03*
X525999D03*
X515499Y284050D03*
X516899Y306950D03*
X520499Y353550D03*
X509999Y382550D03*
X518999Y416550D03*
X511299Y449150D03*
X519499Y471550D03*
Y489050D03*
X508699Y498950D03*
X518999Y508550D03*
X514499Y546050D03*
X509999Y640550D03*
Y655050D03*
Y672550D03*
X527499Y747150D03*
X525499Y772450D03*
X511199Y782050D03*
X512899Y823550D03*
X526499Y851150D03*
X512899Y842550D03*
X510899Y868150D03*
X522499Y876050D03*
X521999Y895550D03*
X506899Y919950D03*
Y900950D03*
X521999Y914550D03*
X516499Y957050D03*
X514499Y975550D03*
Y990050D03*
Y1007550D03*
X513999Y1046050D03*
Y1027050D03*
X518999Y1103050D03*
X511999Y1115550D03*
X527499Y1181550D03*
X527999Y1212550D03*
X527499Y1200550D03*
X507199Y1224350D03*
X525999Y1231050D03*
X507199Y1252350D03*
Y1243350D03*
X525999Y1245550D03*
X527499Y1278150D03*
X525999Y1263050D03*
X518499Y1346950D03*
X523499Y1360050D03*
X508599Y1370550D03*
X523499Y1379050D03*
X523999Y1391050D03*
X516999Y1418050D03*
Y1437050D03*
X517499Y1449050D03*
X518899Y1530150D03*
X510100Y1579800D03*
X508199Y1610450D03*
X518499Y1643950D03*
X509199Y1660550D03*
X507399Y1683350D03*
X522300Y1739200D03*
X508200Y1758200D03*
X515499Y1779050D03*
X526499Y1801150D03*
X514199Y1815750D03*
X517499Y1855450D03*
X519399Y1876750D03*
Y1904750D03*
Y1895750D03*
X518399Y1923250D03*
Y1951250D03*
Y1942250D03*
X509299Y1977250D03*
X511999Y1987550D03*
X535999Y6550D03*
X541499Y25050D03*
X541999Y46550D03*
X541499Y63550D03*
X541999Y79050D03*
Y93550D03*
Y108050D03*
Y125550D03*
X541499Y145050D03*
Y164050D03*
X528799Y199950D03*
X542499Y185050D03*
X533499Y217550D03*
X540499Y255050D03*
X536499Y283050D03*
X544799Y293950D03*
X540099Y306550D03*
X548100Y362200D03*
X530999Y381550D03*
X538799Y445050D03*
X539799Y466050D03*
X539299Y485550D03*
X535499Y545050D03*
X538999Y562050D03*
X534499Y640050D03*
Y654550D03*
Y672050D03*
X547999Y728550D03*
Y743050D03*
Y760550D03*
X547499Y780050D03*
X534499Y805950D03*
X547499Y799050D03*
X541399Y854450D03*
Y873450D03*
X539299Y935850D03*
X540299Y956850D03*
X540899Y981450D03*
Y1000450D03*
X541899Y1021450D03*
X534599Y1048550D03*
X535599Y1069550D03*
X538499Y1103050D03*
X548999Y1116050D03*
X529499D03*
X546499Y1180750D03*
Y1195250D03*
X547099Y1202750D03*
Y1230750D03*
Y1221750D03*
X548799Y1252850D03*
Y1267350D03*
X530499Y1297050D03*
X545099Y1355250D03*
X540399Y1382150D03*
X538799Y1409750D03*
X536799Y1436350D03*
X528499Y1460250D03*
X546099Y1467550D03*
X538999Y1528350D03*
X529799Y1555050D03*
X533800Y1575500D03*
X529499Y1616550D03*
X528999Y1604550D03*
X532499Y1635550D03*
X532599Y1655650D03*
X532499Y1669550D03*
Y1688550D03*
X532999Y1700550D03*
X538299Y1721050D03*
X532499Y1763050D03*
X539499Y1788150D03*
X544300Y1784638D03*
X531799Y1818450D03*
X538999Y1855950D03*
X547999Y1892350D03*
X533499Y1884050D03*
X547999Y1911350D03*
X533499Y1912050D03*
Y1903050D03*
X547999Y1920350D03*
X532499Y1930550D03*
X546999Y1938850D03*
X532499Y1949550D03*
X546999Y1966850D03*
Y1957850D03*
X546299Y1977250D03*
X528799Y1976750D03*
X532499Y1958550D03*
X531500Y1987500D03*
X551499Y6550D03*
X568099Y72550D03*
Y91550D03*
X569099Y112550D03*
X562799Y127750D03*
Y146750D03*
X563799Y167750D03*
X565999Y199950D03*
X568499Y217550D03*
X552999D03*
X557999Y322550D03*
Y326550D03*
X558099Y335050D03*
X557933Y331010D03*
X555999Y412550D03*
X556499Y467550D03*
Y485050D03*
X555999Y504550D03*
X558499Y562550D03*
Y616050D03*
X554304Y615840D03*
X554499Y624550D03*
X558699D03*
X554499Y620050D03*
X558709Y620245D03*
X565699Y710650D03*
X549999Y710050D03*
X562999Y898050D03*
X560999Y916550D03*
Y931050D03*
Y948550D03*
X560499Y968050D03*
Y987050D03*
X560999Y999050D03*
X558999Y1017550D03*
Y1032050D03*
X558499Y1069050D03*
X558999Y1049550D03*
X558499Y1088050D03*
X568499Y1101550D03*
X553999Y1103050D03*
X564499Y1116050D03*
X567999Y1187550D03*
Y1215550D03*
Y1206550D03*
X565999Y1234050D03*
Y1248550D03*
X566399Y1273850D03*
X549399Y1274850D03*
X561099Y1301050D03*
X549399Y1293850D03*
Y1302850D03*
X555699Y1322950D03*
X559099Y1343250D03*
X557499Y1424050D03*
Y1443050D03*
Y1452050D03*
X563499Y1486550D03*
Y1492050D03*
Y1497550D03*
Y1503550D03*
X567999Y1549950D03*
X552199Y1576650D03*
X552099Y1601950D03*
X569499Y1610550D03*
X553399Y1624550D03*
X569499Y1619550D03*
X554199Y1651950D03*
X555199Y1674750D03*
X555399Y1689350D03*
X555899Y1706750D03*
X556199Y1727050D03*
X560399Y1792550D03*
X555500Y1802700D03*
X554499Y1855950D03*
X562599Y1893450D03*
Y1874450D03*
Y1902450D03*
X561599Y1920950D03*
Y1948950D03*
Y1939950D03*
X570299Y1976250D03*
X568999Y1987050D03*
X553499D03*
X570999Y6050D03*
X588499Y6550D03*
X587999Y25050D03*
X588499Y46550D03*
X587999Y63550D03*
X588499Y125550D03*
X587999Y145050D03*
Y164050D03*
X588999Y185050D03*
X587999Y217050D03*
X572999Y255050D03*
Y269550D03*
Y287050D03*
X572499Y306550D03*
Y325550D03*
X573499Y346550D03*
X579899Y375750D03*
X577399Y420050D03*
X578399Y441050D03*
X577899Y460550D03*
X576099Y481850D03*
X577099Y502850D03*
X576599Y522350D03*
X579499Y561550D03*
X573499Y658550D03*
Y673050D03*
Y690550D03*
X586299Y711250D03*
X577999Y732050D03*
X575999Y750550D03*
Y765050D03*
Y782550D03*
X575499Y802050D03*
Y821050D03*
X576499Y842050D03*
X578299Y895650D03*
Y914650D03*
X583299Y961450D03*
X570899Y946850D03*
X583299Y980450D03*
X570899Y965850D03*
X571899Y986850D03*
X573499Y1036550D03*
Y1055550D03*
X574499Y1076550D03*
X588499Y1101550D03*
X578999Y1114550D03*
X582699Y1233250D03*
X583299Y1255250D03*
X582699Y1247750D03*
X583299Y1274250D03*
X579299Y1300750D03*
X583299Y1283250D03*
X581999Y1370150D03*
X580999Y1412750D03*
X575699Y1438950D03*
X582999Y1461250D03*
X590599Y1483450D03*
X582299Y1534150D03*
X588099Y1572050D03*
X573400Y1577600D03*
X588000Y1604000D03*
X590799Y1627850D03*
X580799Y1646150D03*
X572999Y1675550D03*
X590599Y1694450D03*
X572999Y1694550D03*
Y1703550D03*
X580299Y1722550D03*
X582599Y1740050D03*
X573999Y1855450D03*
X588899Y1882350D03*
X575999Y1888050D03*
X588899Y1910350D03*
Y1901350D03*
X575999Y1907050D03*
X587899Y1928850D03*
X576499Y1919050D03*
X574999Y1934550D03*
X587899Y1956850D03*
Y1947850D03*
X574999Y1953550D03*
X585799Y1976250D03*
X575499Y1965550D03*
X588499Y1986550D03*
X608499Y6550D03*
X603999Y35350D03*
Y54350D03*
X604999Y75350D03*
X603999Y133750D03*
Y152750D03*
X604999Y173750D03*
X605499Y217550D03*
X599299Y344650D03*
X600299Y365650D03*
X599799Y385150D03*
X607399Y380250D03*
X592999Y407550D03*
Y422050D03*
Y439550D03*
X592499Y459050D03*
Y478050D03*
X593499Y499050D03*
X606499Y584550D03*
X595999Y624050D03*
Y609550D03*
Y641550D03*
X605299Y661750D03*
X609499Y708050D03*
X597999Y690050D03*
X607499Y726550D03*
Y741050D03*
Y758550D03*
X606999Y778050D03*
Y797050D03*
X603499Y904050D03*
X601499Y922550D03*
Y937050D03*
Y954550D03*
X600999Y1002050D03*
X611399Y1026650D03*
X598999Y1020550D03*
X611399Y1045650D03*
X598999Y1035050D03*
X612399Y1066650D03*
X598999Y1052550D03*
X598499Y1072050D03*
X605999Y1102050D03*
X598499Y1091050D03*
X598999Y1114550D03*
X603899Y1157850D03*
X597599Y1196050D03*
X596599Y1215050D03*
X600899Y1238650D03*
X598499Y1280550D03*
Y1261550D03*
X598999Y1292550D03*
X608899Y1305050D03*
X605599Y1326350D03*
X606199Y1338250D03*
X599499Y1351550D03*
X599999Y1382550D03*
X599499Y1370550D03*
X604899Y1407750D03*
X601299Y1447650D03*
X610899Y1496750D03*
X599799Y1544650D03*
X611900Y1577900D03*
X612499Y1615550D03*
X611999Y1603550D03*
X600599Y1645450D03*
X593399Y1668850D03*
X609499Y1675050D03*
Y1692050D03*
X607599Y1716450D03*
X606999Y1745550D03*
X593299Y1760950D03*
X608599Y1810750D03*
X595199Y1820910D03*
X611999Y1855950D03*
X591499D03*
X602799Y1887350D03*
Y1906350D03*
X601799Y1933850D03*
X602799Y1915350D03*
X601799Y1952850D03*
Y1961850D03*
X605299Y1975750D03*
X605999Y1987050D03*
X625999Y7050D03*
X624499Y23050D03*
X624999Y44550D03*
X624499Y61550D03*
X624999Y123550D03*
X624499Y143050D03*
Y162050D03*
X625499Y183050D03*
X623899Y202550D03*
X625499Y217550D03*
X627999Y262550D03*
Y248050D03*
Y280050D03*
X627499Y299550D03*
X628200Y320000D03*
X628499Y339550D03*
X632399Y358750D03*
X620999Y411550D03*
X621999Y432550D03*
X621499Y452050D03*
Y466550D03*
Y484050D03*
X613700Y504600D03*
X625999Y585050D03*
X620499Y623550D03*
Y609050D03*
X631999Y639650D03*
X622999Y672050D03*
Y689550D03*
X629099Y714050D03*
X633499Y750150D03*
X621499Y767150D03*
X621999Y835050D03*
X612999Y854550D03*
X629499Y853050D03*
Y868550D03*
X613499Y868050D03*
X616699Y948250D03*
Y967250D03*
X617699Y988250D03*
X631999Y1001550D03*
X629999Y1020050D03*
Y1034550D03*
Y1052050D03*
X629499Y1071550D03*
Y1090550D03*
X616499Y1115050D03*
X627699Y1143550D03*
X628699Y1164550D03*
X626199Y1183450D03*
X630499Y1243950D03*
X617599Y1246250D03*
X618199Y1268250D03*
X617599Y1260750D03*
X618199Y1296250D03*
Y1287250D03*
X631799Y1322650D03*
X617899Y1360850D03*
X632499Y1347950D03*
X625499Y1383450D03*
X627499Y1406050D03*
X626799Y1432350D03*
X625199Y1489150D03*
X617699Y1530350D03*
X623499Y1564050D03*
X633499Y1615450D03*
X628499Y1636650D03*
X627299Y1659550D03*
X625499Y1725050D03*
X619499Y1803150D03*
X627273Y1793905D03*
X626999Y1800050D03*
X632799Y1820450D03*
X627494Y1829068D03*
X627499Y1855950D03*
X630699Y1872750D03*
Y1891750D03*
Y1900750D03*
X616499Y1913050D03*
Y1894050D03*
X629699Y1919250D03*
X616499Y1922050D03*
X629699Y1947250D03*
Y1938250D03*
X615499Y1940550D03*
X622799Y1976250D03*
X615499Y1959550D03*
Y1968550D03*
X626999Y1987050D03*
X645499Y7050D03*
X651799Y40650D03*
Y59650D03*
X652799Y80650D03*
X649899Y138350D03*
Y157350D03*
X650899Y178350D03*
X642999Y218050D03*
X653999Y286550D03*
X635399Y376250D03*
X643599Y395950D03*
X644599Y416950D03*
X644099Y450950D03*
Y436450D03*
X642499Y525750D03*
X643499Y546750D03*
X642999Y566250D03*
X646999Y584550D03*
X640599Y604650D03*
X645099Y639150D03*
X647499Y657050D03*
Y671550D03*
X648999Y702350D03*
X647499Y689050D03*
X651999Y718350D03*
X647399Y742150D03*
X653099Y803350D03*
X645799Y816650D03*
X641599Y843250D03*
Y862250D03*
X642599Y883250D03*
X639499Y952150D03*
Y971150D03*
X633999Y1103050D03*
X641799Y1137650D03*
X650299Y1153150D03*
X651299Y1174150D03*
X650599Y1182050D03*
X651599Y1203050D03*
X638999Y1267550D03*
Y1286550D03*
Y1295550D03*
X654499Y1354050D03*
Y1373050D03*
X652999Y1403550D03*
Y1418050D03*
Y1435550D03*
X636799Y1461250D03*
X643099Y1541350D03*
X652399Y1575850D03*
X639200Y1576200D03*
X635500Y1603900D03*
X652499Y1618550D03*
Y1609550D03*
X649399Y1644950D03*
X635099Y1691150D03*
X642499Y1709050D03*
X650399Y1771250D03*
X642400Y1800100D03*
X633837Y1807384D03*
X640999Y1815550D03*
X644049Y1810834D03*
X645099Y1877550D03*
X645399Y1906150D03*
X646799Y1926450D03*
X644999Y1934050D03*
Y1953050D03*
X643799Y1976250D03*
X645499Y1965050D03*
X642499Y1987050D03*
X660999Y7050D03*
X674999Y20550D03*
X675499Y42050D03*
Y74550D03*
X674999Y59050D03*
X675499Y89050D03*
Y103550D03*
Y121050D03*
X674999Y140550D03*
Y159550D03*
X675999Y180550D03*
X662499Y218050D03*
X656499Y307050D03*
Y324550D03*
X655999Y344050D03*
X659899Y363250D03*
X666999Y476550D03*
Y491050D03*
Y508550D03*
X666499Y528050D03*
Y547050D03*
X667499Y568050D03*
X674999Y601550D03*
X665999Y623550D03*
X673999Y645150D03*
X665499Y766550D03*
X664999Y786050D03*
Y805050D03*
X665999Y826050D03*
X663999Y844550D03*
Y876550D03*
Y859050D03*
X663499Y896050D03*
Y915050D03*
X664499Y936050D03*
X658999Y959050D03*
X656999Y977550D03*
Y992050D03*
X673999Y1017550D03*
X656999Y1009550D03*
X673999Y1036550D03*
X656499Y1029050D03*
X674699Y1061450D03*
X656499Y1048050D03*
X674699Y1080450D03*
X669499Y1116550D03*
X674999Y1134950D03*
X667199Y1152850D03*
X668199Y1173850D03*
X670199Y1192750D03*
X671199Y1213750D03*
X668699Y1227650D03*
X657099Y1272850D03*
X657799Y1288450D03*
X672999Y1303450D03*
X656399Y1307050D03*
X671999Y1324950D03*
X665699Y1337250D03*
X654999Y1385050D03*
X659699Y1445950D03*
X665699Y1462250D03*
X656099Y1479550D03*
X672399Y1508750D03*
X673699Y1535350D03*
X662099Y1549650D03*
X670699Y1603150D03*
X671399Y1625350D03*
X657099Y1668850D03*
X674999Y1676550D03*
X656499Y1697050D03*
X675499Y1738050D03*
X665399Y1752350D03*
X675499Y1757050D03*
X675999Y1769050D03*
X659159Y1792278D03*
X659549Y1815384D03*
X667999Y1870950D03*
X669399Y1855350D03*
X674899Y1892350D03*
X661299Y1890050D03*
X674899Y1911350D03*
X661299Y1909050D03*
X674899Y1920350D03*
X661299Y1918050D03*
X673899Y1938850D03*
X660299Y1936550D03*
Y1955550D03*
X673899Y1966850D03*
Y1957850D03*
X660299Y1964550D03*
X659299Y1976250D03*
X661999Y1986550D03*
X680499Y6550D03*
X694999Y62650D03*
Y81650D03*
X695999Y102650D03*
X688999Y196550D03*
X677999Y218050D03*
X683499Y263050D03*
Y248550D03*
X680500Y280700D03*
X682999Y300050D03*
Y319050D03*
X683999Y340050D03*
X694999Y480550D03*
X695999Y501550D03*
X695499Y521050D03*
X691399Y548350D03*
X692399Y569350D03*
X691899Y588850D03*
X690499Y623050D03*
X693999Y648150D03*
X678499Y671050D03*
X679299Y703050D03*
X678499Y688550D03*
X681899Y713650D03*
X696299Y741850D03*
X694599Y763450D03*
X685999Y780050D03*
X687099Y804650D03*
Y823650D03*
X688099Y844650D03*
X687099Y896350D03*
Y915350D03*
X688099Y936350D03*
X678299Y978350D03*
Y997350D03*
X694999Y993050D03*
X692999Y1011550D03*
Y1026050D03*
Y1043550D03*
X692499Y1063050D03*
Y1082050D03*
X689999Y1105550D03*
X695999Y1203050D03*
Y1235050D03*
Y1217550D03*
X684299Y1249550D03*
X695999Y1323350D03*
X677999Y1347550D03*
X694999Y1360050D03*
X680299Y1365850D03*
X694999Y1379050D03*
X681299Y1393150D03*
X692999Y1406550D03*
X694999Y1388050D03*
X678299Y1425050D03*
X692999Y1421050D03*
X686999Y1468850D03*
X685299Y1551950D03*
X681299Y1579150D03*
X693599Y1602450D03*
X686699Y1638650D03*
X691999Y1660550D03*
X693099Y1722350D03*
X690499Y1744950D03*
X694599Y1768450D03*
X693549Y1793134D03*
X686473Y1818375D03*
X686999Y1870250D03*
X690899Y1855850D03*
X696299Y1898850D03*
X676399Y1901150D03*
X695299Y1926450D03*
X685499Y1940050D03*
X696299Y1976250D03*
X678799Y1975750D03*
X685499Y1959050D03*
Y1968050D03*
X679499Y1987050D03*
X697999Y7050D03*
X712499Y6050D03*
X699699Y141750D03*
Y160750D03*
X700699Y181750D03*
X711999Y218050D03*
X711499Y252550D03*
X711999Y307550D03*
Y293050D03*
Y325050D03*
X711499Y344550D03*
X712699Y434450D03*
X713699Y455450D03*
X713199Y474950D03*
Y489450D03*
X712599Y521050D03*
X713599Y542050D03*
X713099Y561550D03*
X699999Y610050D03*
X717099Y636050D03*
X702999Y656050D03*
Y688050D03*
Y670550D03*
X710899Y751150D03*
X716599Y736850D03*
X706999Y792550D03*
X707499Y773050D03*
X706999Y811550D03*
X707999Y832550D03*
X705999Y851050D03*
Y865550D03*
X707399Y899550D03*
Y918550D03*
X706499Y942550D03*
X713999Y1017050D03*
Y1031550D03*
X713499Y1068550D03*
X713999Y1049050D03*
X709999Y1105550D03*
X700499Y1118550D03*
X704299Y1132650D03*
X716999Y1148150D03*
X697499Y1153550D03*
X717999Y1169150D03*
X697499Y1172550D03*
X713399Y1178750D03*
X697999Y1184550D03*
X713599Y1214650D03*
X714399Y1199750D03*
X708699Y1243550D03*
X709699Y1264550D03*
X707899Y1346250D03*
X702299Y1404450D03*
X713899Y1386450D03*
X716899Y1459850D03*
X700899Y1450250D03*
X716199Y1503050D03*
X714599Y1533950D03*
X708899Y1549250D03*
X698599Y1568550D03*
X706700Y1579900D03*
X717099Y1702450D03*
X702599Y1730550D03*
X715999Y1744050D03*
X709099Y1751850D03*
X715999Y1763050D03*
Y1772050D03*
X706549Y1793634D03*
X705000Y1811900D03*
X711500Y1817700D03*
X704300Y1828400D03*
X697999Y1844550D03*
X706399Y1855850D03*
X705599Y1891850D03*
X716599Y1918450D03*
X698299Y1948050D03*
X711899Y1944050D03*
X709199Y1962950D03*
X717999Y1987550D03*
X702499D03*
X729999Y6550D03*
X725499Y23550D03*
X725999Y45050D03*
X725499Y62050D03*
X725999Y77550D03*
Y92050D03*
Y106550D03*
X738199Y137450D03*
X725999Y124050D03*
X725499Y143550D03*
Y162550D03*
X726499Y183550D03*
X728899Y204550D03*
X729499Y218550D03*
X723200Y275500D03*
X737999Y467050D03*
X738999Y488050D03*
X738499Y507550D03*
Y539550D03*
Y522050D03*
X737999Y559050D03*
X731499Y572050D03*
Y586550D03*
Y604050D03*
X721499Y617550D03*
X729699Y640350D03*
X723499Y654850D03*
X739399Y688150D03*
X720899Y712250D03*
X732499Y729250D03*
X727099Y715050D03*
X733799Y761450D03*
X723999Y783350D03*
Y802350D03*
X724999Y823350D03*
X728499Y841850D03*
X729999Y862850D03*
Y881850D03*
X730999Y902850D03*
X723699Y936250D03*
Y955250D03*
X724699Y976250D03*
X734999Y1030550D03*
Y1045050D03*
Y1062550D03*
X727499Y1106050D03*
X737999Y1119050D03*
X720499Y1118550D03*
X727499Y1132650D03*
X737999Y1159550D03*
Y1187550D03*
Y1178550D03*
X735999Y1206050D03*
X725499Y1231650D03*
X735999Y1220550D03*
X725499Y1250650D03*
X723499Y1278150D03*
X725499Y1259650D03*
X723499Y1292650D03*
X719199Y1322350D03*
X739199Y1348950D03*
X734199Y1373850D03*
X736199Y1399050D03*
X737799Y1428350D03*
X721899Y1419050D03*
X719499Y1446650D03*
X729199Y1492750D03*
X735799Y1533650D03*
X734499Y1563550D03*
X722199Y1564250D03*
X719999Y1605050D03*
X732999Y1620050D03*
X738799Y1677250D03*
X727399Y1694350D03*
X739199Y1716750D03*
X721199Y1723750D03*
X729999Y1756450D03*
X729499Y1778750D03*
X728099Y1844750D03*
X723199Y1867950D03*
X725899Y1855350D03*
X732999Y1868550D03*
X728299Y1888850D03*
X732199Y1878750D03*
X728799Y1908150D03*
Y1933050D03*
X736799Y1919450D03*
X730499Y1954650D03*
X721499Y1974550D03*
X737499Y1987050D03*
X749499Y6550D03*
X751499Y48350D03*
X757499Y44050D03*
Y63050D03*
X758499Y84050D03*
X752099Y112150D03*
X757999Y154550D03*
Y159050D03*
X753999Y154550D03*
Y159050D03*
X749499Y218550D03*
X755499Y314550D03*
X755346Y319149D03*
X751539Y313984D03*
X751499Y318050D03*
X749899Y398550D03*
X750899Y419550D03*
X750399Y453550D03*
Y439050D03*
X755199Y488150D03*
X756199Y509150D03*
X755699Y528650D03*
X754499Y564650D03*
X755499Y585650D03*
X754999Y605150D03*
X744999Y626550D03*
X751499Y679148D03*
X757400Y686300D03*
X747999Y670750D03*
X754999Y694050D03*
X749999Y700050D03*
X749499Y716050D03*
X744999Y715550D03*
X749999Y720050D03*
X745499D03*
X749799Y767450D03*
X743099Y785350D03*
X751999Y817050D03*
X751499Y855550D03*
Y836550D03*
X751599Y887350D03*
Y906350D03*
X752599Y927350D03*
X749999Y946550D03*
Y965550D03*
X751399Y1004550D03*
X750999Y986550D03*
X751399Y1023550D03*
X752399Y1052550D03*
X753999Y1100050D03*
X755499Y1119050D03*
X749999Y1119550D03*
X748999Y1115550D03*
X748499Y1111550D03*
X758799Y1171150D03*
Y1190150D03*
Y1199150D03*
X756799Y1232150D03*
Y1217650D03*
X757399Y1258650D03*
Y1239650D03*
X740499Y1252550D03*
X757399Y1267650D03*
X740499Y1270050D03*
X740799Y1298750D03*
X755399Y1300650D03*
Y1286150D03*
X742099Y1320650D03*
X754999Y1420050D03*
Y1437550D03*
X741099Y1450250D03*
Y1498150D03*
X747199Y1509150D03*
X755499Y1507550D03*
X751000Y1517000D03*
X757500Y1522500D03*
X751000Y1521000D03*
Y1525000D03*
X755499Y1568550D03*
X743400Y1578700D03*
X751300Y1604900D03*
X756299Y1679050D03*
X750099Y1694950D03*
X756499Y1712150D03*
X747499Y1734350D03*
X756900Y1766000D03*
X752900D03*
X751899Y1752150D03*
X747799Y1766750D03*
X751999Y1775550D03*
X756617Y1780067D03*
X752657Y1779496D03*
X755999Y1775550D03*
X753558Y1769946D03*
X757518Y1770517D03*
X744049Y1791634D03*
X740549Y1802634D03*
X753949Y1798194D03*
X740549Y1810384D03*
X747599Y1844250D03*
X744699Y1868450D03*
X758399Y1868350D03*
X743399Y1855850D03*
X743799Y1888850D03*
X753699Y1879250D03*
X755299Y1902150D03*
X739799D03*
X755500Y1914500D03*
X746499Y1974250D03*
X754999Y1987550D03*
X764999Y6550D03*
X763399Y24150D03*
X774399Y54050D03*
X775399Y80250D03*
X778399Y105250D03*
X767399Y140150D03*
X760799Y181950D03*
X779399Y200550D03*
X766999Y219050D03*
X774999Y476550D03*
Y462050D03*
Y494050D03*
X774499Y513550D03*
Y532550D03*
X775499Y553550D03*
X777499Y638050D03*
X764599Y655750D03*
X777499Y664550D03*
X771800Y686600D03*
X766499Y699050D03*
Y705550D03*
X778999Y806950D03*
X763099Y796350D03*
X775199Y839250D03*
Y858250D03*
X776199Y879250D03*
X772199Y920650D03*
Y939650D03*
X773199Y960650D03*
X776899Y988050D03*
Y1007050D03*
X777899Y1028050D03*
X760999Y1095550D03*
X773499Y1101050D03*
X769499D03*
X773499Y1105050D03*
X769499D03*
X762499Y1335550D03*
X779399Y1361850D03*
X762499Y1353050D03*
X773999Y1393450D03*
X763399Y1401450D03*
X769300Y1488100D03*
X779000Y1488400D03*
X771399Y1474550D03*
X770999Y1500050D03*
X780499D03*
X773499Y1509050D03*
X769499D03*
X768500Y1577500D03*
X776999Y1647650D03*
X765099Y1664950D03*
X770399Y1699650D03*
X779999Y1717050D03*
X770099Y1730350D03*
X779899Y1748150D03*
X765600Y1756800D03*
X767159Y1792364D03*
X765099Y1844750D03*
X779699Y1867950D03*
X779399Y1855850D03*
X763899D03*
X780799Y1888850D03*
X763299Y1888350D03*
X769199Y1879250D03*
X774499Y1908050D03*
X765999D03*
X773999Y1923550D03*
X767999Y1923050D03*
X774499Y1930050D03*
X768999D03*
X775999Y1916050D03*
X768499Y1917550D03*
X777499Y1987550D03*
X784499Y6050D03*
X801999Y6550D03*
X796999Y27050D03*
X797499Y48550D03*
X796999Y65550D03*
X797499Y81050D03*
Y95550D03*
Y110050D03*
X796599Y123450D03*
X797499Y127550D03*
X796999Y147050D03*
Y166050D03*
X797999Y187050D03*
X786499Y219050D03*
X800999Y216550D03*
X796873Y307571D03*
Y303071D03*
Y298571D03*
Y294071D03*
X789999Y570050D03*
Y602050D03*
Y584550D03*
X785499Y641050D03*
X794999Y664550D03*
X786500Y686100D03*
X798000Y686400D03*
X782999Y699550D03*
X794331Y698353D03*
Y702853D03*
Y707353D03*
Y711853D03*
X799385Y761436D03*
X802499Y814550D03*
X801999Y834050D03*
Y853050D03*
X800999Y892550D03*
Y907050D03*
Y924550D03*
X800499Y944050D03*
Y963050D03*
X801499Y984050D03*
X800999Y1005550D03*
Y1020050D03*
Y1037550D03*
X783999Y1096550D03*
X789499Y1099550D03*
X802499Y1097566D03*
X798499D03*
X790999Y1194550D03*
Y1175550D03*
X791499Y1206550D03*
X789499Y1225050D03*
Y1257050D03*
Y1239550D03*
X788999Y1278150D03*
X791999Y1294450D03*
X795299Y1326650D03*
X799999Y1340550D03*
X798299Y1344250D03*
X799999Y1358050D03*
X781999Y1434650D03*
X786500Y1488600D03*
X801300Y1489000D03*
X786999Y1506550D03*
X795999Y1509550D03*
Y1504550D03*
Y1518550D03*
Y1514050D03*
X797299Y1646650D03*
X802899Y1670550D03*
X782999Y1668050D03*
Y1687050D03*
X783499Y1699050D03*
X794499Y1734550D03*
X787900Y1758800D03*
X801099Y1844750D03*
X785599D03*
X791799Y1855850D03*
X797199Y1868450D03*
X788699Y1878750D03*
X783499Y1907050D03*
X790499Y1913050D03*
X795526Y1909696D03*
X795493Y1913696D03*
X795501Y1917696D03*
X795499Y1922050D03*
X789299Y1983850D03*
X792999Y1987550D03*
X818999Y6050D03*
X817599Y43750D03*
X813299Y49350D03*
Y68350D03*
X814299Y89350D03*
X813299Y110850D03*
X821199Y137450D03*
X805899Y126150D03*
X809373Y307571D03*
Y297571D03*
Y292571D03*
X808999Y303050D03*
X821499Y314050D03*
X819299Y413250D03*
Y394250D03*
X820299Y434250D03*
X802999Y466050D03*
X803999Y487050D03*
X803499Y506550D03*
Y538550D03*
Y521050D03*
X802999Y558050D03*
X814499Y569550D03*
Y601550D03*
Y584050D03*
X809700Y686300D03*
X806300Y670600D03*
X806831Y701853D03*
Y706853D03*
X806999Y697050D03*
X806831Y711853D03*
X811499Y767550D03*
Y782050D03*
Y799550D03*
X802999Y874050D03*
X811499Y1097050D03*
X807499D03*
X807341Y1111216D03*
Y1101216D03*
X806999Y1106050D03*
X807341Y1116216D03*
X808299Y1175850D03*
X806599Y1189750D03*
X803599Y1211050D03*
X810199Y1229350D03*
Y1248350D03*
Y1257350D03*
X808199Y1275850D03*
Y1290350D03*
X822199Y1335250D03*
X819199Y1353550D03*
X806499Y1390550D03*
X803299Y1426650D03*
X806499Y1408050D03*
X805899Y1464250D03*
X809245Y1508722D03*
Y1503722D03*
Y1518722D03*
X808999Y1513550D03*
X813300Y1604100D03*
X803599Y1618350D03*
X814599Y1642650D03*
X823499Y1674050D03*
X808899Y1698450D03*
X823499Y1693050D03*
Y1702050D03*
X824100Y1719900D03*
X819400Y1721900D03*
X819200Y1727100D03*
X808299Y1755250D03*
X809299Y1856350D03*
X818900Y1870800D03*
X806199Y1879250D03*
X807936Y1914865D03*
Y1910365D03*
X807997Y1922865D03*
X808005Y1918865D03*
X813599Y1979950D03*
X812499Y1987050D03*
X836499Y6550D03*
X824899Y25150D03*
X844799Y19850D03*
X839999Y46050D03*
X840499Y55050D03*
X840999Y62550D03*
X841499Y71550D03*
X843499Y82550D03*
X838999Y85050D03*
X837999Y91050D03*
X838499Y107050D03*
Y99550D03*
X839499Y119050D03*
X837499Y138550D03*
X838499Y145050D03*
X838999Y313550D03*
X838499Y352050D03*
X839299Y390950D03*
Y409950D03*
X840299Y430950D03*
X824899Y500450D03*
X825899Y521450D03*
X825399Y540950D03*
X834599Y543050D03*
X835599Y564050D03*
X835099Y583550D03*
X841000Y671100D03*
X836149Y714050D03*
X835999Y767050D03*
X837799Y754150D03*
X835999Y781550D03*
Y799050D03*
X825199Y850850D03*
X827699Y873450D03*
Y892450D03*
X828699Y913450D03*
X826999Y963150D03*
Y982150D03*
X827999Y1003150D03*
X841999Y1118550D03*
X836149D03*
X839999Y1157550D03*
X831499Y1181550D03*
Y1209550D03*
Y1200550D03*
X829499Y1228050D03*
Y1242550D03*
X828199Y1267850D03*
X826199Y1294450D03*
X831499Y1324950D03*
X841999Y1341050D03*
Y1358550D03*
X825500Y1379000D03*
X834499Y1397550D03*
X836600Y1416500D03*
X843999Y1523550D03*
X839499D03*
X839899Y1562050D03*
X825999Y1578050D03*
X826499Y1609050D03*
X827199Y1622750D03*
X841499Y1638950D03*
X837199Y1660550D03*
X839199Y1683550D03*
X842799Y1701150D03*
X829200Y1719800D03*
X844499Y1788050D03*
X842500Y1799000D03*
X827999Y1791550D03*
X829799Y1856350D03*
X833199Y1868450D03*
X842199Y1879250D03*
X833100Y1878500D03*
X843999Y1928550D03*
X838999D03*
X840999Y1970550D03*
X829499Y1980250D03*
X829999Y1987550D03*
X855999Y6550D03*
X860799Y24150D03*
X865499Y39550D03*
X854499D03*
X856499Y71050D03*
X855499Y82050D03*
X845999Y111050D03*
X853999Y132550D03*
X865499Y125550D03*
X849999Y145550D03*
X863999Y313550D03*
X858400Y352300D03*
X847999Y352550D03*
X854499Y387550D03*
Y373050D03*
Y405050D03*
X853999Y424550D03*
Y443550D03*
X854999Y464550D03*
X860199Y525050D03*
X861199Y546050D03*
X860699Y565550D03*
X861800Y591200D03*
X860499Y607550D03*
X860796Y678632D03*
X859999Y713050D03*
Y767550D03*
X856299Y753150D03*
X846799Y754150D03*
X865000Y752100D03*
X859999Y782050D03*
Y799550D03*
X847799Y828250D03*
X857099Y873450D03*
X866199Y920350D03*
Y901350D03*
X850999Y962550D03*
Y943550D03*
X851999Y983550D03*
X859999Y1118550D03*
X846499Y1170450D03*
X856400Y1157700D03*
X848999Y1158050D03*
X863300Y1153800D03*
X845799Y1190450D03*
X849799Y1199750D03*
X851999Y1237550D03*
Y1218550D03*
X852499Y1249550D03*
X850499Y1268050D03*
X860099Y1295450D03*
X850499Y1300050D03*
Y1282550D03*
X861999Y1522550D03*
X850099Y1572250D03*
X858400Y1561900D03*
X850499Y1562050D03*
X865300Y1557700D03*
X864000Y1578200D03*
X849900Y1605100D03*
X852499Y1621350D03*
X855799Y1658250D03*
X855350Y1703201D03*
X864099Y1683550D03*
X853799Y1790850D03*
X863099Y1813150D03*
X862499Y1823550D03*
X854977Y1818994D03*
X861414Y1928550D03*
X864414Y1940050D03*
X850499Y1977950D03*
X856999Y1970050D03*
X849999Y1970550D03*
X865200Y1968000D03*
X864999Y1987050D03*
X849499D03*
X871499Y6550D03*
X885999Y21150D03*
X883999Y39050D03*
X881499Y70550D03*
X866999D03*
X876999Y82050D03*
X867499D03*
X886499Y99550D03*
Y104550D03*
X872499Y133050D03*
X875499Y125550D03*
X871499Y146050D03*
X871786Y218924D03*
Y203924D03*
X887400Y233555D03*
X871786Y233924D03*
X887400Y259700D03*
X879878Y247724D03*
X870600Y346700D03*
X875799Y386250D03*
Y405250D03*
X876799Y426250D03*
X884399Y443450D03*
Y462450D03*
X885399Y483450D03*
X870719Y609705D03*
X870773Y624705D03*
X870719Y639705D03*
X887401Y665000D03*
X881125Y652050D03*
X871786Y679436D03*
Y709482D03*
X871499Y689436D03*
X866499Y724550D03*
X871385Y719436D03*
X884499Y767050D03*
Y781550D03*
Y799050D03*
X873999Y830550D03*
Y845050D03*
Y862550D03*
X886999Y907350D03*
X867199Y941350D03*
X886999Y947250D03*
X870777Y1014948D03*
X870468Y1030227D03*
X886919Y1044478D03*
X870298Y1045227D03*
X880033Y1058592D03*
X887400Y1070600D03*
X871399Y1182850D03*
Y1201850D03*
Y1210850D03*
X869399Y1229350D03*
Y1243850D03*
X872099Y1268150D03*
X871399Y1291450D03*
X875399Y1322650D03*
X873499Y1356050D03*
X868499Y1392550D03*
Y1410050D03*
X871836Y1420460D03*
X886913Y1449010D03*
X871836Y1435460D03*
X879727Y1463696D03*
X871836Y1450460D03*
X887499Y1476050D03*
X873099Y1572550D03*
X886900Y1604100D03*
X866499Y1603050D03*
Y1612050D03*
X868099Y1635650D03*
X887299Y1620050D03*
X877699Y1646650D03*
X882999Y1678250D03*
X879200Y1698700D03*
X879900Y1709300D03*
X883900Y1709500D03*
X875900D03*
X872950Y1744401D03*
X866699Y1770950D03*
X879399Y1798150D03*
X869634Y1826876D03*
X871836Y1840972D03*
X887499Y1855550D03*
X869999Y1855972D03*
X887401Y1881500D03*
X879399Y1974550D03*
X873399Y1963650D03*
X868699Y1983250D03*
X884499Y1986550D03*
X890999Y6050D03*
X908499Y6550D03*
X905499Y56550D03*
X904999Y61550D03*
X904499Y74050D03*
X904999Y67550D03*
X890459Y100116D03*
X890499Y104550D03*
X889999Y132550D03*
X891999Y146050D03*
X906999Y243150D03*
Y224150D03*
X907999Y264150D03*
X906399Y295250D03*
Y314250D03*
X907399Y335250D03*
X904999Y370550D03*
Y385050D03*
Y402550D03*
X904499Y422050D03*
Y441050D03*
X905499Y462050D03*
X903999Y574378D03*
X898999Y622050D03*
Y604550D03*
X894000Y642400D03*
X900999Y652550D03*
Y670050D03*
X895999Y702550D03*
Y720050D03*
X898499Y830050D03*
Y844550D03*
X889699Y876050D03*
X898499Y862050D03*
X897299Y1182450D03*
X887999Y1209350D03*
X892499Y1224550D03*
Y1252550D03*
Y1243550D03*
X890499Y1271050D03*
Y1285550D03*
X890999Y1336550D03*
Y1354050D03*
X894499Y1423550D03*
Y1441050D03*
X895499Y1488050D03*
X902759Y1509585D03*
X894499Y1522050D03*
Y1539550D03*
X907500Y1604000D03*
X895999Y1661250D03*
X903599Y1686850D03*
X893200Y1721300D03*
X902900Y1709800D03*
X893200Y1730000D03*
X904814Y1789113D03*
X903299Y1814750D03*
X894999Y1829050D03*
X905299Y1852650D03*
X894000Y1868452D03*
X900299Y1876950D03*
X897299Y1904150D03*
X907599Y1930050D03*
X897599Y1938750D03*
X904299Y1954950D03*
X901999Y1987050D03*
X923999Y6050D03*
X928499Y51550D03*
X920900Y54700D03*
X928999Y56050D03*
X928499Y60550D03*
X928999Y65550D03*
X913699Y484650D03*
Y503650D03*
X914699Y524650D03*
X918999Y641550D03*
Y656050D03*
Y673550D03*
X918499Y693050D03*
Y712050D03*
X921899Y744850D03*
X919499Y733050D03*
X921899Y759350D03*
Y776850D03*
X921399Y796350D03*
X922399Y836350D03*
X921399Y815350D03*
X920399Y854850D03*
Y869350D03*
Y886850D03*
X919899Y906350D03*
Y925350D03*
X920899Y946350D03*
X921499Y999050D03*
Y1013550D03*
Y1031050D03*
X920999Y1050550D03*
Y1069550D03*
X925499Y1103550D03*
X921999Y1090550D03*
X925499Y1118050D03*
Y1135550D03*
X924999Y1174050D03*
Y1155050D03*
X925999Y1195050D03*
Y1207050D03*
Y1221550D03*
Y1239050D03*
X925499Y1258550D03*
Y1277550D03*
X926499Y1298550D03*
X928499Y1325350D03*
X925999Y1365050D03*
Y1379550D03*
Y1397050D03*
X925499Y1416550D03*
Y1435550D03*
X926499Y1456550D03*
X924999Y1485550D03*
Y1471050D03*
Y1503050D03*
X914599Y1521650D03*
X924499Y1522550D03*
X910899Y1549250D03*
X924499Y1541550D03*
X909700Y1576400D03*
X925499Y1562550D03*
X925599Y1612050D03*
X923599Y1634350D03*
X908899Y1630050D03*
X914899Y1657550D03*
X922599Y1682150D03*
X911299Y1800850D03*
X928000Y1818500D03*
X922899Y1853650D03*
X914999Y1868050D03*
Y1887050D03*
X914899Y1912450D03*
X915499Y1899050D03*
X916599Y1942650D03*
X914899Y1972250D03*
X921499Y1986550D03*
X941499Y6550D03*
X929999Y32550D03*
X940499Y33050D03*
X945499Y33550D03*
X943499Y48050D03*
Y55050D03*
Y72550D03*
X942999Y61550D03*
Y66550D03*
X943499Y78050D03*
X939199Y142050D03*
X932499Y191550D03*
Y206050D03*
Y223550D03*
X931999Y243050D03*
Y262050D03*
X932999Y283050D03*
X933499Y304050D03*
Y318550D03*
Y336050D03*
X932999Y355550D03*
Y374550D03*
X933999Y395550D03*
X933499Y429550D03*
Y415050D03*
Y447050D03*
X932999Y466550D03*
Y485550D03*
X933999Y506550D03*
X935499Y539050D03*
Y524550D03*
Y556550D03*
X934999Y576050D03*
X950299Y599650D03*
X934999Y595050D03*
X950299Y614150D03*
X935999Y616050D03*
X950299Y631650D03*
X949799Y651150D03*
Y670150D03*
X950799Y691150D03*
X944499Y750050D03*
Y735550D03*
Y767550D03*
X943999Y787050D03*
Y806050D03*
X944999Y827050D03*
X942999Y845550D03*
Y877550D03*
Y860050D03*
X942499Y897050D03*
Y916050D03*
X943499Y937050D03*
X949299Y977450D03*
Y991950D03*
Y1009450D03*
X948799Y1047950D03*
Y1028950D03*
X949799Y1068950D03*
Y1080950D03*
X950699Y1107750D03*
Y1122250D03*
Y1139750D03*
X950199Y1159250D03*
Y1178250D03*
X950699Y1262750D03*
Y1281750D03*
X943799Y1342950D03*
Y1380850D03*
X944000Y1391900D03*
X946700Y1426500D03*
X944000Y1511300D03*
X943199Y1531650D03*
X933199Y1577550D03*
X944499Y1632650D03*
X950100Y1626100D03*
X940499Y1656950D03*
X941499Y1679550D03*
X931499Y1702050D03*
X949799Y1756250D03*
X941800Y1787700D03*
X941499Y1776250D03*
X934200Y1793500D03*
X932199Y1801850D03*
X937199Y1869950D03*
X937499Y1893850D03*
X938199Y1917150D03*
X947499Y1936050D03*
X930999Y1931050D03*
X945199Y1946350D03*
X930999Y1950050D03*
X946199Y1966650D03*
X931499Y1962050D03*
X930199Y1979550D03*
X936999Y1986550D03*
X960999Y6550D03*
X954799Y17850D03*
X965999Y47050D03*
Y56050D03*
Y64050D03*
X966499Y73050D03*
Y82050D03*
X968399Y137150D03*
X967399Y180350D03*
X958799Y167350D03*
X956099Y181350D03*
X952799Y199150D03*
Y213650D03*
Y231150D03*
X952299Y250650D03*
Y269650D03*
X953299Y290650D03*
X952799Y324650D03*
Y310150D03*
Y342150D03*
X952299Y361650D03*
Y380650D03*
X953299Y401650D03*
X954799Y434150D03*
Y419650D03*
Y451650D03*
X966199Y473350D03*
Y492350D03*
X951799Y489650D03*
X967199Y513350D03*
X951799Y504150D03*
Y521650D03*
X951299Y560150D03*
Y541150D03*
X966799Y566350D03*
X952299Y581150D03*
X966799Y585350D03*
X967799Y606350D03*
X969499Y639050D03*
Y653550D03*
Y671050D03*
X968999Y709550D03*
Y690550D03*
X969999Y730550D03*
Y744250D03*
Y758750D03*
Y776250D03*
X969499Y795750D03*
Y814750D03*
X970499Y835750D03*
Y847750D03*
Y862250D03*
X969999Y899250D03*
X970499Y879750D03*
X969999Y918250D03*
X970999Y939250D03*
X971999Y996550D03*
Y1011050D03*
Y1028550D03*
X971499Y1067050D03*
Y1048050D03*
X951199Y1211250D03*
Y1199250D03*
Y1225750D03*
Y1243250D03*
X951699Y1302750D03*
X965099Y1324350D03*
X952499Y1361850D03*
X964400Y1409700D03*
X966600Y1529100D03*
X961400Y1528700D03*
X961900Y1522400D03*
X967100Y1522800D03*
X962100Y1516000D03*
X967300Y1516400D03*
X961600Y1534400D03*
X972000Y1547500D03*
X966100D03*
X960900Y1547100D03*
X961400Y1540800D03*
X966600Y1541200D03*
X966800Y1534800D03*
X961600Y1552900D03*
X966800Y1553300D03*
X972000Y1566000D03*
X966100D03*
X960900Y1565600D03*
X961400Y1559300D03*
X966600Y1559700D03*
X961900Y1572400D03*
X967100Y1572800D03*
X966400Y1585500D03*
X961200Y1585100D03*
X961700Y1578800D03*
X966900Y1579200D03*
X966500Y1592000D03*
X961300Y1591600D03*
X966300Y1598400D03*
X961100Y1598000D03*
X960600Y1604300D03*
X971700Y1604700D03*
X965800D03*
X957799Y1646950D03*
X955499Y1690850D03*
X958799Y1715750D03*
X965349Y1742000D03*
X954499Y1783550D03*
X971000Y1803000D03*
X971500Y1871500D03*
X966799Y1892150D03*
X955499Y1893050D03*
Y1902050D03*
X954099Y1915450D03*
X955799Y1951950D03*
X971499Y1956050D03*
Y1937050D03*
X953799Y1977950D03*
X971499Y1965050D03*
X956499Y1986050D03*
X976499Y6550D03*
X974699Y21450D03*
X991399Y22450D03*
X977399Y44050D03*
X974699Y64650D03*
X991999Y56050D03*
X983099Y83650D03*
X977699Y109150D03*
X981099Y123450D03*
X988699Y174350D03*
X982999Y189050D03*
Y203550D03*
Y221050D03*
X982499Y240550D03*
Y259550D03*
X983499Y280550D03*
X983999Y301550D03*
Y316050D03*
Y333550D03*
X983499Y353050D03*
Y372050D03*
X983999Y412550D03*
X984499Y393050D03*
X983999Y427050D03*
Y444550D03*
X983499Y464050D03*
Y483050D03*
X984499Y504050D03*
X985999Y536550D03*
Y522050D03*
Y554050D03*
X985499Y573550D03*
Y592550D03*
X986499Y613550D03*
X992999Y894550D03*
Y913550D03*
X972499Y1088050D03*
X975999Y1101050D03*
Y1115550D03*
X975499Y1152550D03*
X975999Y1133050D03*
X975499Y1171550D03*
X976499Y1192550D03*
Y1204550D03*
Y1219050D03*
Y1236550D03*
X975999Y1256050D03*
Y1275050D03*
X976999Y1296050D03*
X975100Y1342600D03*
X976499Y1362550D03*
Y1377050D03*
X992500Y1397300D03*
X973200Y1516400D03*
X972500Y1529100D03*
X973000Y1522800D03*
X972700Y1534800D03*
X972500Y1541200D03*
X972700Y1553300D03*
X972500Y1559700D03*
X973000Y1572800D03*
X972300Y1585500D03*
X972800Y1579200D03*
X972400Y1592000D03*
X972200Y1598400D03*
X989999Y1718050D03*
X993299Y1734350D03*
X976600Y1757100D03*
X976399Y1772250D03*
Y1791150D03*
X974699Y1914450D03*
X991999Y1915750D03*
X992299Y1929050D03*
X980999Y1933350D03*
X987999Y1949050D03*
Y1971950D03*
X989999Y1962650D03*
X973999Y1986550D03*
X995999Y6050D03*
X1013499Y6550D03*
X1002699Y40050D03*
X1005299Y71350D03*
X994399Y101250D03*
X1010599Y115550D03*
X1005299Y179950D03*
Y194450D03*
Y211950D03*
X1004799Y231450D03*
Y250450D03*
X1005799Y271450D03*
X1005299Y305450D03*
Y290950D03*
Y322950D03*
X1004799Y342450D03*
Y361450D03*
X1005799Y382450D03*
X1007299Y400450D03*
Y432450D03*
Y414950D03*
X1000699Y463350D03*
Y482350D03*
X1001699Y503350D03*
X1003999Y526850D03*
X1003499Y546350D03*
Y565350D03*
X1004499Y586350D03*
X1005999Y618850D03*
Y604350D03*
Y636350D03*
X994999Y747550D03*
Y733050D03*
Y765050D03*
X994499Y784550D03*
Y803550D03*
X995499Y824550D03*
X993499Y857550D03*
Y843050D03*
Y875050D03*
X994499Y941550D03*
X993999Y934550D03*
X994499Y956050D03*
Y973550D03*
X993999Y993050D03*
Y1012050D03*
X994999Y1033050D03*
Y1045050D03*
X998599Y1110950D03*
Y1096450D03*
Y1128450D03*
X998099Y1147950D03*
Y1166950D03*
X999099Y1187950D03*
Y1214450D03*
Y1199950D03*
Y1231950D03*
X998599Y1251450D03*
Y1270450D03*
X999599Y1291450D03*
X996500Y1324800D03*
X1000700Y1358100D03*
X994200Y1421500D03*
X1008999Y1702450D03*
X1008599Y1716050D03*
X994999Y1748950D03*
X999999Y1775250D03*
X1009999Y1797450D03*
X993499Y1805550D03*
X1007599Y1818450D03*
X993499Y1824550D03*
X1003599Y1846650D03*
X993499Y1833550D03*
X1011299Y1860650D03*
X995699Y1858950D03*
X1001599Y1921450D03*
X1000999Y1946350D03*
X1002500Y1953500D03*
X1005000Y1980500D03*
X994999Y1986550D03*
X1022000Y15500D03*
X1020499Y50550D03*
X1020999Y33050D03*
Y70050D03*
Y85550D03*
Y105050D03*
X1020499Y122550D03*
X1020999Y158550D03*
X1021499Y141050D03*
Y178050D03*
Y193550D03*
Y213050D03*
X1020999Y230550D03*
Y252050D03*
X1020499Y269550D03*
X1020999Y304550D03*
Y289050D03*
Y324050D03*
X1020499Y341550D03*
Y391550D03*
X1020999Y374050D03*
Y411050D03*
Y426550D03*
Y446050D03*
X1020499Y463550D03*
X1021999Y486550D03*
X1021499Y504050D03*
X1021999Y539050D03*
Y523550D03*
Y558550D03*
X1021499Y576050D03*
X1020499Y623050D03*
X1020999Y605550D03*
Y642550D03*
Y658050D03*
Y677550D03*
X1020499Y695050D03*
X1020999Y720050D03*
X1020499Y737550D03*
X1020999Y772550D03*
Y757050D03*
Y792050D03*
X1020499Y809550D03*
Y828050D03*
X1019999Y845550D03*
X1020499Y865050D03*
Y880550D03*
X1019999Y917550D03*
X1020499Y900050D03*
X1019999Y934050D03*
X1019499Y951550D03*
X1019999Y971050D03*
Y986550D03*
X1019499Y1023550D03*
X1019999Y1006050D03*
Y1043050D03*
Y1058550D03*
X1020499Y1081550D03*
X1019999Y1099050D03*
X1020499Y1118550D03*
Y1134050D03*
X1019499Y1146050D03*
X1018999Y1163550D03*
X1019499Y1183050D03*
Y1198550D03*
X1016999Y1219050D03*
X1016499Y1236550D03*
X1016999Y1256050D03*
Y1271550D03*
X1016499Y1301050D03*
X1022599Y1322950D03*
X1023300Y1344400D03*
X1024300Y1365200D03*
Y1393600D03*
X1022299Y1715750D03*
X1016899Y1731650D03*
X1020299Y1746650D03*
X1015299Y1765950D03*
X1026899Y1768550D03*
X1022999Y1784550D03*
X1022499Y1802050D03*
X1022999Y1821550D03*
Y1837050D03*
X1020999Y1860050D03*
X1020499Y1877550D03*
X1020999Y1912550D03*
Y1897050D03*
X1017499Y1954550D03*
X1017999Y1937050D03*
X1023000Y1973000D03*
X1017999Y1987050D03*
G54D15*
X51999Y767050D03*
X47999Y767550D03*
X52499Y771550D03*
X47999D03*
X97300Y1564100D03*
X110999Y1130550D03*
X115200Y1130300D03*
X110999Y1126050D03*
Y1122050D03*
Y1118050D03*
X114999Y1126050D03*
Y1122050D03*
Y1118050D03*
X122600Y1565000D03*
X119999Y1978550D03*
X119499Y1972550D03*
X144149Y1230113D03*
Y1226113D03*
Y1222113D03*
X143700Y1332500D03*
X129100Y1564700D03*
X127200Y1569800D03*
X127499Y1978550D03*
X133499D03*
X132999Y1972550D03*
X126999D03*
X150500Y545000D03*
X148499Y1222113D03*
Y1226113D03*
X148486Y1230113D03*
X189499Y39150D03*
X179999Y442550D03*
X179649Y438550D03*
X183999D03*
Y442550D03*
Y447050D03*
X179999D03*
X172000Y931600D03*
X174250Y1694500D03*
X197999Y39900D03*
X193999D03*
X208499Y45650D03*
X199999Y46050D03*
X194499Y44050D03*
X204496Y846111D03*
X204649Y838050D03*
X208999D03*
X209000Y846113D03*
X204649Y842113D03*
X208986D03*
X224750Y1483950D03*
X247800Y269700D03*
X246800Y677100D03*
X247500Y1085500D03*
X231800Y1887100D03*
X293998Y361114D03*
Y356614D03*
Y352114D03*
X289998Y361114D03*
Y356614D03*
Y352114D03*
X294999Y767050D03*
X290999D03*
X294999Y762550D03*
Y758050D03*
X290999Y762550D03*
Y758050D03*
X293998Y1573614D03*
Y1569114D03*
X289998Y1573614D03*
Y1569114D03*
X293998Y1578114D03*
X289998D03*
X293999Y1971050D03*
Y1966550D03*
Y1962050D03*
X289499Y1961550D03*
Y1966550D03*
Y1971050D03*
X305998Y352114D03*
X306999Y758050D03*
X305998Y1569114D03*
X305999Y1964050D03*
Y1969550D03*
X323400Y105200D03*
X717000Y1812384D03*
X781478Y363924D03*
X776978D03*
X772478Y359924D03*
Y363924D03*
X771196Y764382D03*
Y760382D03*
X775696Y764382D03*
X780196D03*
X780333Y1165892D03*
X775833D03*
X771333Y1161892D03*
Y1165892D03*
X778327Y1569796D03*
X773327Y1565796D03*
X773827Y1569796D03*
X775814Y1975699D03*
X770814Y1971713D03*
X771814Y1975713D03*
X784478Y355424D03*
Y359924D03*
X783196Y760382D03*
Y755882D03*
X783333Y1157392D03*
Y1161892D03*
X785827Y1561296D03*
Y1565796D03*
X782827Y1569796D03*
X783814Y1967213D03*
Y1971713D03*
X784016Y1975708D03*
X827500Y274500D03*
X829800Y666650D03*
X825700Y1083100D03*
X827700Y1487600D03*
X828500Y1877800D03*
X902999Y22050D03*
X902499Y35050D03*
X917499Y21550D03*
X909499D03*
X909999Y35550D03*
X916499Y36050D03*
X972000Y1442000D03*
Y1437500D03*
X971700Y1448300D03*
X962500Y1436500D03*
Y1441000D03*
X952800Y1437500D03*
Y1442000D03*
X962200Y1447300D03*
X952500Y1448300D03*
X971500Y1467500D03*
X971700Y1457800D03*
Y1462300D03*
Y1452800D03*
X962000Y1466500D03*
X952300Y1467500D03*
X962200Y1451800D03*
X952500Y1452800D03*
X962200Y1456800D03*
Y1461300D03*
X952500Y1457800D03*
Y1462300D03*
X966000Y1475000D03*
X958800Y1472500D03*
X966000Y1479500D03*
Y1484000D03*
X958800Y1477000D03*
Y1481500D03*
X965700Y1489300D03*
X958500Y1486800D03*
X960200Y1495300D03*
X951500D03*
X960049Y1500300D03*
X951349D03*
X960049Y1504800D03*
X951349D03*
X973500Y1483000D03*
Y1478500D03*
X973200Y1488300D03*
X973500Y1474000D03*
X972549Y1502300D03*
Y1506800D03*
X972700Y1497300D03*
G54D17*
X78150Y28858D03*
Y178464D03*
Y434370D03*
Y583976D03*
Y839882D03*
Y989488D03*
Y1245394D03*
Y1395000D03*
Y1650906D03*
Y1800512D03*
X158071Y191614D03*
Y341220D03*
Y597126D03*
Y746732D03*
Y1002638D03*
Y1152244D03*
Y1408150D03*
Y1557756D03*
Y1813662D03*
Y1963268D03*
X886417Y191614D03*
Y341220D03*
Y597126D03*
Y746732D03*
Y1002638D03*
Y1152244D03*
Y1408150D03*
Y1557756D03*
Y1813662D03*
Y1963268D03*
G54D10*
X-38436Y23633D03*
X-36811Y1104775D03*
X-35919Y1969497D03*
X1072493Y21507D03*
X1075940Y1769358D03*
G54D12*
X29531Y309549D03*
Y1029510D03*
X17720Y1903132D03*
X271657Y267699D03*
Y673210D03*
Y1078722D03*
Y1484234D03*
Y1889746D03*
X994098Y149588D03*
Y673210D03*
Y1068880D03*
G54D13*
X9843Y353144D03*
Y717711D03*
Y762617D03*
Y875216D03*
Y1337396D03*
Y1701963D03*
Y1746869D03*
Y1859468D03*
G54D21*
X1019291Y1416024D03*
Y1694212D03*
G54D18*
X129921Y17716D03*
X994093Y1889751D03*
G54D19*
X180299Y1626550D03*
X180000Y1619600D03*
X180299Y1634550D03*
X179733Y1630590D03*
X195700Y1619100D03*
X195600Y1623700D03*
X371999Y15550D03*
X376499D03*
X369999Y23550D03*
Y19050D03*
X380999Y15550D03*
X382499Y20050D03*
G54D20*
X882700Y1738300D03*
X886900Y1737900D03*
%LPC*%
G75*
G54D22*
G01X-87137Y-139897D02*
Y-107897D01*
G01X-75137Y-123897D02*
G02I-12000J0D01*
G01X-80287D02*
G02I-6850J0D01*
G01X-71137D02*
X-103137D01*
G01X-71137Y-139897D02*
Y-219897D01*
G01D02*
X1129963D01*
G01X-71137Y-175397D02*
X1129963D01*
G01X-71137Y-139897D02*
X1129963D01*
G01X342463D02*
Y-219897D01*
G01X479963Y-139897D02*
Y-219897D01*
G01X594963Y-139897D02*
Y-219897D01*
G01X762463Y-139897D02*
Y-219897D01*
G01X932463Y-139897D02*
Y-219897D01*
G01X1129963Y-139897D02*
Y-219897D01*
G01X1157963Y-123897D02*
G02I-12000J0D01*
G01X1152813D02*
G02I-6850J0D01*
G01X1161963D02*
X1129963D01*
G01X1145963Y-139897D02*
Y-107897D01*
G54D23*
G01X-53190Y-209897D02*
Y-192397D01*
G01X-44894D02*
X-53190Y-203189D01*
G01X-43584Y-209897D02*
X-49479Y-198231D01*
G01X-35909Y-209897D02*
Y-192397D01*
X-25865Y-209897D01*
Y-192397D01*
G01X-13387Y-209897D02*
X-15134Y-209605D01*
X-16662Y-208439D01*
X-17972Y-206689D01*
X-18846Y-204647D01*
X-19282Y-202314D01*
Y-199980D01*
X-18846Y-197647D01*
X-17972Y-195605D01*
X-16662Y-193856D01*
X-15134Y-192689D01*
X-13387Y-192397D01*
X-11641Y-192689D01*
X-10112Y-193856D01*
X-8802Y-195605D01*
X-7928Y-197647D01*
X-7492Y-199980D01*
Y-202314D01*
X-7928Y-204647D01*
X-8802Y-206689D01*
X-10112Y-208439D01*
X-11641Y-209605D01*
X-13387Y-209897D01*
G01X-472D02*
X8698Y-192397D01*
G01X-472D02*
X8698Y-209897D01*
G01X34310D02*
Y-192397D01*
X38676D01*
X40423Y-193272D01*
X41733Y-194439D01*
X42825Y-196188D01*
X43698Y-198231D01*
X43916Y-201147D01*
X43698Y-204064D01*
X42825Y-206106D01*
X41733Y-207856D01*
X40423Y-209022D01*
X38676Y-209897D01*
X34310D01*
G01X52246D02*
Y-192397D01*
X57705D01*
X59451Y-193272D01*
X60543Y-194439D01*
X60980Y-196772D01*
X60543Y-199106D01*
X59233Y-200564D01*
X57705Y-201439D01*
X52246D01*
G01X57705D02*
X60980Y-209897D01*
G01X71493Y-192397D02*
X76733D01*
G01X74113D02*
Y-209897D01*
G01X71493D02*
X76733D01*
G01X86154Y-192397D02*
X91613Y-209897D01*
X97072Y-192397D01*
G01X113480Y-209897D02*
X104746D01*
Y-192397D01*
X113480D01*
G01X109986Y-200855D02*
X104746D01*
G01X139746Y-209897D02*
Y-192397D01*
X144986D01*
X146733Y-193272D01*
X148043Y-195314D01*
X148480Y-197647D01*
X148043Y-199980D01*
X146951Y-201730D01*
X144986Y-202606D01*
X139746D01*
G01X157246Y-192397D02*
Y-209897D01*
X165980D01*
G01X173654D02*
X179113Y-192397D01*
X184572Y-209897D01*
G01X182606Y-203772D02*
X175619D01*
G01X191591Y-209897D02*
Y-192397D01*
X201635Y-209897D01*
Y-192397D01*
G01X218480Y-209897D02*
X209746D01*
Y-192397D01*
X218480D01*
G01X214986Y-200855D02*
X209746D01*
G01X250859Y-200564D02*
X251733Y-199689D01*
X252388Y-198231D01*
X252825Y-196188D01*
X252388Y-194439D01*
X251515Y-193272D01*
X249986Y-192397D01*
X244091D01*
Y-209897D01*
X251296D01*
X252825Y-208731D01*
X253698Y-206980D01*
X254135Y-204939D01*
X253698Y-202897D01*
X252388Y-201147D01*
X250859Y-200564D01*
X244091D01*
G01X266613Y-209897D02*
X264866Y-209605D01*
X263338Y-208439D01*
X262028Y-206689D01*
X261154Y-204647D01*
X260718Y-202314D01*
Y-199980D01*
X261154Y-197647D01*
X262028Y-195605D01*
X263338Y-193856D01*
X264866Y-192689D01*
X266613Y-192397D01*
X268359Y-192689D01*
X269888Y-193856D01*
X271198Y-195605D01*
X272072Y-197647D01*
X272508Y-199980D01*
Y-202314D01*
X272072Y-204647D01*
X271198Y-206689D01*
X269888Y-208439D01*
X268359Y-209605D01*
X266613Y-209897D01*
G01X278654D02*
X284113Y-192397D01*
X289572Y-209897D01*
G01X287606Y-203772D02*
X280619D01*
G01X297246Y-209897D02*
Y-192397D01*
X302705D01*
X304451Y-193272D01*
X305543Y-194439D01*
X305980Y-196772D01*
X305543Y-199106D01*
X304233Y-200564D01*
X302705Y-201439D01*
X297246D01*
G01X302705D02*
X305980Y-209897D01*
G01X314310D02*
Y-192397D01*
X318676D01*
X320423Y-193272D01*
X321733Y-194439D01*
X322825Y-196188D01*
X323698Y-198231D01*
X323916Y-201147D01*
X323698Y-204064D01*
X322825Y-206106D01*
X321733Y-207856D01*
X320423Y-209022D01*
X318676Y-209897D01*
X314310D01*
G01X94686Y-164897D02*
Y-147397D01*
X100363Y-161980D01*
X106040Y-147397D01*
Y-164897D01*
G01X117863D02*
X116553Y-164605D01*
X115243Y-163439D01*
X114369Y-161397D01*
X113933Y-159064D01*
X114369Y-156730D01*
X115243Y-154689D01*
X116553Y-153522D01*
X117863Y-153231D01*
X119173Y-153522D01*
X120483Y-154689D01*
X121356Y-156730D01*
X121575Y-159064D01*
X121356Y-161397D01*
X120483Y-163439D01*
X119173Y-164605D01*
X117863Y-164897D01*
G01X139293Y-147397D02*
Y-164897D01*
G01Y-162273D02*
X138420Y-163731D01*
X137109Y-164605D01*
X135581Y-164897D01*
X133835Y-164314D01*
X132525Y-162856D01*
X131651Y-161106D01*
X131433Y-159064D01*
X131651Y-157022D01*
X132525Y-155272D01*
X133835Y-153814D01*
X135581Y-153231D01*
X137109Y-153522D01*
X138201Y-154106D01*
X139293Y-155272D01*
G01X149588Y-157022D02*
X156575D01*
X155920Y-154980D01*
X154828Y-153814D01*
X153300Y-153231D01*
X151771Y-153522D01*
X150461Y-154397D01*
X149588Y-156439D01*
X149151Y-158189D01*
Y-159939D01*
X149588Y-161689D01*
X150680Y-163439D01*
X151990Y-164605D01*
X153518Y-164897D01*
X155046Y-164314D01*
X156575Y-162564D01*
G01X170363Y-164897D02*
Y-147397D01*
G01X376163Y-209897D02*
Y-192397D01*
X373543Y-195897D01*
G01Y-209897D02*
X378783D01*
G01X389515Y-195314D02*
X390825Y-193564D01*
X392353Y-192689D01*
X394100Y-192397D01*
X396283Y-192980D01*
X397811Y-194439D01*
X398248Y-196188D01*
X398030Y-197939D01*
X397156Y-199397D01*
X392790Y-202314D01*
X390825Y-204355D01*
X389515Y-207273D01*
X389078Y-209897D01*
X398248D01*
G01X413783D02*
Y-192397D01*
X405704Y-204939D01*
X416622D01*
G01X423860Y-206397D02*
X425169Y-208439D01*
X426916Y-209605D01*
X428881Y-209897D01*
X430628Y-209605D01*
X432375Y-208147D01*
X433466Y-206397D01*
X433685Y-204647D01*
X433248Y-202606D01*
X431720Y-201147D01*
X430191Y-200564D01*
X428226D01*
G01X430191D02*
X431501Y-199689D01*
X432593Y-198231D01*
X433030Y-196481D01*
X432593Y-194730D01*
X431501Y-193272D01*
X429536Y-192397D01*
X427571Y-192689D01*
X425606Y-193856D01*
G01X442015Y-195314D02*
X443325Y-193564D01*
X444853Y-192689D01*
X446600Y-192397D01*
X448783Y-192980D01*
X450311Y-194439D01*
X450748Y-196188D01*
X450530Y-197939D01*
X449656Y-199397D01*
X445290Y-202314D01*
X443325Y-204355D01*
X442015Y-207273D01*
X441578Y-209897D01*
X450748D01*
G01X363046Y-164897D02*
Y-147397D01*
X368286D01*
X370033Y-148272D01*
X371343Y-150314D01*
X371780Y-152647D01*
X371343Y-154980D01*
X370251Y-156730D01*
X368286Y-157606D01*
X363046D01*
G01X389716Y-148856D02*
X388406Y-147980D01*
X386878Y-147397D01*
X385131D01*
X383166Y-148272D01*
X381638Y-149730D01*
X380546Y-151481D01*
X379673Y-154397D01*
X379454Y-157022D01*
X379891Y-159647D01*
X380546Y-161397D01*
X381856Y-163147D01*
X383385Y-164314D01*
X384913Y-164897D01*
X386441D01*
X387970Y-164314D01*
X389280Y-163439D01*
X390372Y-162273D01*
G01X404159Y-155564D02*
X405033Y-154689D01*
X405688Y-153231D01*
X406125Y-151188D01*
X405688Y-149439D01*
X404815Y-148272D01*
X403286Y-147397D01*
X397391D01*
Y-164897D01*
X404596D01*
X406125Y-163731D01*
X406998Y-161980D01*
X407435Y-159939D01*
X406998Y-157897D01*
X405688Y-156147D01*
X404159Y-155564D01*
X397391D01*
G01X413363Y-170730D02*
X426463D01*
G01X432391Y-164897D02*
Y-147397D01*
X442435Y-164897D01*
Y-147397D01*
G01X454913Y-164897D02*
X453166Y-164605D01*
X451638Y-163439D01*
X450328Y-161689D01*
X449454Y-159647D01*
X449018Y-157314D01*
Y-154980D01*
X449454Y-152647D01*
X450328Y-150605D01*
X451638Y-148856D01*
X453166Y-147689D01*
X454913Y-147397D01*
X456659Y-147689D01*
X458188Y-148856D01*
X459498Y-150605D01*
X460372Y-152647D01*
X460808Y-154980D01*
Y-157314D01*
X460372Y-159647D01*
X459498Y-161689D01*
X458188Y-163439D01*
X456659Y-164605D01*
X454913Y-164897D01*
G01X505754Y-147397D02*
X511213Y-164897D01*
X516672Y-147397D01*
G01X533080Y-164897D02*
X524346D01*
Y-147397D01*
X533080D01*
G01X529586Y-155855D02*
X524346D01*
G01X541846Y-164897D02*
Y-147397D01*
X547305D01*
X549051Y-148272D01*
X550143Y-149439D01*
X550580Y-151772D01*
X550143Y-154106D01*
X548833Y-155564D01*
X547305Y-156439D01*
X541846D01*
G01X547305D02*
X550580Y-164897D01*
G01X563713Y-165480D02*
X563276Y-165189D01*
Y-164605D01*
X563713Y-164314D01*
X564150Y-164605D01*
Y-165189D01*
X563713Y-165480D01*
G01X537463Y-209897D02*
Y-192397D01*
X534843Y-195897D01*
G01Y-209897D02*
X540083D01*
G01X630546Y-147397D02*
Y-164897D01*
X639280D01*
G01X656343D02*
Y-153231D01*
G01Y-155272D02*
X655470Y-154106D01*
X654159Y-153522D01*
X652631Y-153231D01*
X651103Y-153814D01*
X649793Y-154980D01*
X648919Y-156730D01*
X648483Y-159064D01*
X648919Y-161397D01*
X649793Y-163147D01*
X651103Y-164314D01*
X652631Y-164897D01*
X654159Y-164605D01*
X655470Y-163731D01*
X656343Y-162564D01*
G01X665328Y-170147D02*
X666638Y-170730D01*
X668385Y-170147D01*
X669476Y-168981D01*
X670350Y-167522D01*
X671659Y-162856D01*
X674498Y-153231D01*
G01X667511D02*
X671659Y-162856D01*
G01X684138Y-157022D02*
X691125D01*
X690470Y-154980D01*
X689378Y-153814D01*
X687850Y-153231D01*
X686321Y-153522D01*
X685011Y-154397D01*
X684138Y-156439D01*
X683701Y-158189D01*
Y-159939D01*
X684138Y-161689D01*
X685230Y-163439D01*
X686540Y-164605D01*
X688068Y-164897D01*
X689596Y-164314D01*
X691125Y-162564D01*
G01X701856Y-164897D02*
Y-153231D01*
G01Y-155564D02*
X702948Y-154397D01*
X704040Y-153522D01*
X705568Y-153231D01*
X706659Y-153522D01*
X707970Y-154397D01*
G01X719138Y-162856D02*
X720230Y-164022D01*
X721758Y-164897D01*
X723068D01*
X724378Y-164314D01*
X725251Y-163439D01*
X725688Y-162273D01*
X725470Y-160522D01*
X724596Y-159647D01*
X720666Y-157897D01*
X719793Y-155855D01*
X720230Y-154397D01*
X721103Y-153522D01*
X722413Y-153231D01*
X723723Y-153522D01*
X725033Y-154397D01*
G01X718030Y-192397D02*
Y-209897D01*
X709296D01*
G01X700966Y-207273D02*
X699657Y-208731D01*
X698128Y-209605D01*
X696163Y-209897D01*
X694198Y-209314D01*
X692670Y-208147D01*
X691578Y-206106D01*
X691360Y-203772D01*
X691796Y-201439D01*
X692888Y-199980D01*
X694417Y-198814D01*
X695945Y-198522D01*
X697473Y-198814D01*
X699438Y-199980D01*
X698783Y-192397D01*
X692888D01*
G01X684122D02*
X678663Y-209897D01*
X673204Y-192397D01*
G01X656360Y-193856D02*
X657670Y-192980D01*
X659198Y-192397D01*
X660945D01*
X662910Y-193272D01*
X664438Y-194730D01*
X665530Y-196481D01*
X666403Y-199397D01*
X666622Y-202022D01*
X666185Y-204647D01*
X665530Y-206397D01*
X664220Y-208147D01*
X662691Y-209314D01*
X661163Y-209897D01*
X659635D01*
X658106Y-209314D01*
X656796Y-208439D01*
X655704Y-207273D01*
G01X638860Y-193856D02*
X640170Y-192980D01*
X641698Y-192397D01*
X643445D01*
X645410Y-193272D01*
X646938Y-194730D01*
X648030Y-196481D01*
X648903Y-199397D01*
X649122Y-202022D01*
X648685Y-204647D01*
X648030Y-206397D01*
X646720Y-208147D01*
X645191Y-209314D01*
X643663Y-209897D01*
X642135D01*
X640606Y-209314D01*
X639296Y-208439D01*
X638204Y-207273D01*
G01X781410Y-164897D02*
Y-147397D01*
X785776D01*
X787523Y-148272D01*
X788833Y-149439D01*
X789925Y-151188D01*
X790798Y-153231D01*
X791016Y-156147D01*
X790798Y-159064D01*
X789925Y-161106D01*
X788833Y-162856D01*
X787523Y-164022D01*
X785776Y-164897D01*
X781410D01*
G01X800438Y-157022D02*
X807425D01*
X806770Y-154980D01*
X805678Y-153814D01*
X804150Y-153231D01*
X802621Y-153522D01*
X801311Y-154397D01*
X800438Y-156439D01*
X800001Y-158189D01*
Y-159939D01*
X800438Y-161689D01*
X801530Y-163439D01*
X802840Y-164605D01*
X804368Y-164897D01*
X805896Y-164314D01*
X807425Y-162564D01*
G01X817938Y-162856D02*
X819030Y-164022D01*
X820558Y-164897D01*
X821868D01*
X823178Y-164314D01*
X824051Y-163439D01*
X824488Y-162273D01*
X824270Y-160522D01*
X823396Y-159647D01*
X819466Y-157897D01*
X818593Y-155855D01*
X819030Y-154397D01*
X819903Y-153522D01*
X821213Y-153231D01*
X822523Y-153522D01*
X823833Y-154397D01*
G01X838713Y-153231D02*
Y-164897D01*
G01Y-148564D02*
X838276Y-148272D01*
Y-147689D01*
X838713Y-147397D01*
X839150Y-147689D01*
Y-148272D01*
X838713Y-148564D01*
G01X853156Y-169272D02*
X854685Y-170439D01*
X856431Y-170730D01*
X857959Y-170439D01*
X859270Y-168981D01*
X860143Y-166939D01*
Y-153231D01*
G01Y-155564D02*
X859270Y-154397D01*
X857959Y-153522D01*
X856431Y-153231D01*
X854685Y-153814D01*
X853593Y-154980D01*
X852719Y-157022D01*
X852283Y-159064D01*
X852501Y-160814D01*
X853375Y-162856D01*
X854685Y-164314D01*
X856431Y-164897D01*
X857741Y-164605D01*
X859270Y-163439D01*
X860143Y-162273D01*
G01X870001Y-164897D02*
Y-153231D01*
G01Y-156147D02*
X870875Y-154689D01*
X872185Y-153522D01*
X873931Y-153231D01*
X875459Y-153522D01*
X876770Y-154689D01*
X877425Y-156730D01*
Y-164897D01*
G01X887938Y-157022D02*
X894925D01*
X894270Y-154980D01*
X893178Y-153814D01*
X891650Y-153231D01*
X890121Y-153522D01*
X888811Y-154397D01*
X887938Y-156439D01*
X887501Y-158189D01*
Y-159939D01*
X887938Y-161689D01*
X889030Y-163439D01*
X890340Y-164605D01*
X891868Y-164897D01*
X893396Y-164314D01*
X894925Y-162564D01*
G01X905656Y-164897D02*
Y-153231D01*
G01Y-155564D02*
X906748Y-154397D01*
X907840Y-153522D01*
X909368Y-153231D01*
X910459Y-153522D01*
X911770Y-154397D01*
G01X825596Y-209897D02*
Y-192397D01*
X831055D01*
X832801Y-193272D01*
X833893Y-194439D01*
X834330Y-196772D01*
X833893Y-199106D01*
X832583Y-200564D01*
X831055Y-201439D01*
X825596D01*
G01X831055D02*
X834330Y-209897D01*
G01X847463D02*
X846153Y-209605D01*
X844843Y-208439D01*
X843969Y-206397D01*
X843533Y-204064D01*
X843969Y-201730D01*
X844843Y-199689D01*
X846153Y-198522D01*
X847463Y-198231D01*
X848773Y-198522D01*
X850083Y-199689D01*
X850956Y-201730D01*
X851175Y-204064D01*
X850956Y-206397D01*
X850083Y-208439D01*
X848773Y-209605D01*
X847463Y-209897D01*
G01X861033D02*
Y-192397D01*
G01Y-201147D02*
X862125Y-199397D01*
X863435Y-198522D01*
X864745Y-198231D01*
X866709Y-198814D01*
X868020Y-199980D01*
X868893Y-202022D01*
Y-204355D01*
X868456Y-206689D01*
X867583Y-208439D01*
X866055Y-209605D01*
X864745Y-209897D01*
X863435Y-209605D01*
X862125Y-208731D01*
X861033Y-207273D01*
G01X952413Y-209897D02*
Y-192397D01*
X949793Y-195897D01*
G01Y-209897D02*
X955033D01*
G01X969913Y-192397D02*
X968166Y-192980D01*
X966856Y-194439D01*
X965983Y-196188D01*
X965328Y-198522D01*
X965110Y-201147D01*
X965328Y-203772D01*
X965983Y-206106D01*
X966856Y-207856D01*
X968166Y-209314D01*
X969913Y-209897D01*
X971659Y-209314D01*
X972970Y-207856D01*
X973843Y-206106D01*
X974498Y-203772D01*
X974716Y-201147D01*
X974498Y-198522D01*
X973843Y-196188D01*
X972970Y-194439D01*
X971659Y-192980D01*
X969913Y-192397D01*
G01X983483Y-210480D02*
X991343Y-192397D01*
G01X1004913Y-209897D02*
Y-192397D01*
X1002293Y-195897D01*
G01Y-209897D02*
X1007533D01*
G01X1018265Y-202606D02*
X1019793Y-200564D01*
X1021103Y-199397D01*
X1022850Y-198814D01*
X1024378Y-199397D01*
X1025470Y-200564D01*
X1026343Y-202314D01*
X1026561Y-204355D01*
X1026343Y-206106D01*
X1025470Y-207856D01*
X1024159Y-209314D01*
X1022631Y-209897D01*
X1020885Y-209314D01*
X1019356Y-207564D01*
X1018483Y-204939D01*
X1018265Y-202022D01*
X1018701Y-198231D01*
X1019356Y-196188D01*
X1020448Y-194147D01*
X1021976Y-192689D01*
X1023505Y-192397D01*
X1025033Y-192980D01*
X1026125Y-194439D01*
G01X1035983Y-210480D02*
X1043843Y-192397D01*
G01X1053265Y-195314D02*
X1054575Y-193564D01*
X1056103Y-192689D01*
X1057850Y-192397D01*
X1060033Y-192980D01*
X1061561Y-194439D01*
X1061998Y-196188D01*
X1061780Y-197939D01*
X1060906Y-199397D01*
X1056540Y-202314D01*
X1054575Y-204355D01*
X1053265Y-207273D01*
X1052828Y-209897D01*
X1061998D01*
G01X1074913Y-192397D02*
X1073166Y-192980D01*
X1071856Y-194439D01*
X1070983Y-196188D01*
X1070328Y-198522D01*
X1070110Y-201147D01*
X1070328Y-203772D01*
X1070983Y-206106D01*
X1071856Y-207856D01*
X1073166Y-209314D01*
X1074913Y-209897D01*
X1076659Y-209314D01*
X1077970Y-207856D01*
X1078843Y-206106D01*
X1079498Y-203772D01*
X1079716Y-201147D01*
X1079498Y-198522D01*
X1078843Y-196188D01*
X1077970Y-194439D01*
X1076659Y-192980D01*
X1074913Y-192397D01*
G01X1092413Y-209897D02*
Y-192397D01*
X1089793Y-195897D01*
G01Y-209897D02*
X1095033D01*
G01X1105765Y-195314D02*
X1107075Y-193564D01*
X1108603Y-192689D01*
X1110350Y-192397D01*
X1112533Y-192980D01*
X1114061Y-194439D01*
X1114498Y-196188D01*
X1114280Y-197939D01*
X1113406Y-199397D01*
X1109040Y-202314D01*
X1107075Y-204355D01*
X1105765Y-207273D01*
X1105328Y-209897D01*
X1114498D01*
G01X1000110Y-164897D02*
Y-147397D01*
X1004476D01*
X1006223Y-148272D01*
X1007533Y-149439D01*
X1008625Y-151188D01*
X1009498Y-153231D01*
X1009716Y-156147D01*
X1009498Y-159064D01*
X1008625Y-161106D01*
X1007533Y-162856D01*
X1006223Y-164022D01*
X1004476Y-164897D01*
X1000110D01*
G01X1026343D02*
Y-153231D01*
G01Y-155272D02*
X1025470Y-154106D01*
X1024159Y-153522D01*
X1022631Y-153231D01*
X1021103Y-153814D01*
X1019793Y-154980D01*
X1018919Y-156730D01*
X1018483Y-159064D01*
X1018919Y-161397D01*
X1019793Y-163147D01*
X1021103Y-164314D01*
X1022631Y-164897D01*
X1024159Y-164605D01*
X1025470Y-163731D01*
X1026343Y-162564D01*
G01X1039913Y-147397D02*
Y-164897D01*
G01X1036856Y-153231D02*
X1042970D01*
G01X1054138Y-157022D02*
X1061125D01*
X1060470Y-154980D01*
X1059378Y-153814D01*
X1057850Y-153231D01*
X1056321Y-153522D01*
X1055011Y-154397D01*
X1054138Y-156439D01*
X1053701Y-158189D01*
Y-159939D01*
X1054138Y-161689D01*
X1055230Y-163439D01*
X1056540Y-164605D01*
X1058068Y-164897D01*
X1059596Y-164314D01*
X1061125Y-162564D01*
M02*
